(kicad_sch (version 20230121) (generator eeschema)

  (paper "A3")

  (title_block
    (title "Kria K26 Devboard")
    (date "2024-03-26")
    (rev "1.2.5")
    (comment 1 "www.antmicro.com")
    (comment 2 "Antmicro Ltd.")
  )

  (junction (at 100.838 118.11) (diameter 0) (color 0 0 0 0)
  )
  (junction (at 196.723 127) (diameter 0) (color 0 0 0 0)
  )
  (junction (at 161.798 129.54) (diameter 0) (color 0 0 0 0)
  )
  (junction (at 167.005 168.91) (diameter 0) (color 0 0 0 0)
  )
  (junction (at 269.24 206.375) (diameter 0) (color 0 0 0 0)
  )
  (junction (at 180.848 100.33) (diameter 0) (color 0 0 0 0)
  )
  (junction (at 269.24 122.555) (diameter 0) (color 0 0 0 0)
  )
  (junction (at 269.24 153.035) (diameter 0) (color 0 0 0 0)
  )
  (junction (at 184.658 129.54) (diameter 0) (color 0 0 0 0)
  )
  (junction (at 180.848 116.84) (diameter 0) (color 0 0 0 0)
  )
  (junction (at 138.303 144.78) (diameter 0) (color 0 0 0 0)
  )
  (junction (at 196.723 113.03) (diameter 0) (color 0 0 0 0)
  )
  (junction (at 157.988 117.475) (diameter 0) (color 0 0 0 0)
  )
  (junction (at 95.123 118.11) (diameter 0) (color 0 0 0 0)
  )
  (junction (at 180.848 110.49) (diameter 0) (color 0 0 0 0)
  )
  (junction (at 140.97 168.91) (diameter 0) (color 0 0 0 0)
  )
  (junction (at 269.24 107.315) (diameter 0) (color 0 0 0 0)
  )
  (junction (at 91.313 104.14) (diameter 0) (color 0 0 0 0)
  )
  (junction (at 271.78 201.295) (diameter 0) (color 0 0 0 0)
  )
  (junction (at 269.24 208.915) (diameter 0) (color 0 0 0 0)
  )
  (junction (at 157.988 127) (diameter 0) (color 0 0 0 0)
  )
  (junction (at 180.848 127) (diameter 0) (color 0 0 0 0)
  )
  (junction (at 148.463 144.78) (diameter 0) (color 0 0 0 0)
  )
  (junction (at 196.723 110.49) (diameter 0) (color 0 0 0 0)
  )
  (junction (at 196.723 129.54) (diameter 0) (color 0 0 0 0)
  )
  (junction (at 171.958 144.78) (diameter 0) (color 0 0 0 0)
  )
  (junction (at 271.78 196.215) (diameter 0) (color 0 0 0 0)
  )
  (junction (at 109.093 104.14) (diameter 0) (color 0 0 0 0)
  )
  (junction (at 100.838 120.65) (diameter 0) (color 0 0 0 0)
  )
  (junction (at 184.658 113.03) (diameter 0) (color 0 0 0 0)
  )
  (junction (at 157.988 110.49) (diameter 0) (color 0 0 0 0)
  )
  (junction (at 91.313 120.65) (diameter 0) (color 0 0 0 0)
  )
  (junction (at 161.798 113.03) (diameter 0) (color 0 0 0 0)
  )
  (junction (at 269.24 114.935) (diameter 0) (color 0 0 0 0)
  )
  (junction (at 269.24 145.415) (diameter 0) (color 0 0 0 0)
  )
  (junction (at 157.988 100.965) (diameter 0) (color 0 0 0 0)
  )

  (no_connect (at 273.05 188.595))
  (no_connect (at 273.05 155.575))
  (no_connect (at 273.05 168.275))
  (no_connect (at 273.05 112.395))
  (no_connect (at 273.05 191.135))
  (no_connect (at 273.05 193.675))
  (no_connect (at 273.05 120.015))
  (no_connect (at 273.05 186.055))
  (no_connect (at 273.05 165.735))
  (no_connect (at 273.05 170.815))
  (no_connect (at 273.05 173.355))
  (no_connect (at 273.05 109.855))
  (no_connect (at 273.05 117.475))

  (wire (pts (xy 138.303 146.05) (xy 138.303 144.78))
    (stroke (width 0) (type default))
  )
  (wire (pts (xy 266.7 125.095) (xy 273.05 125.095))
    (stroke (width 0) (type default))
  )
  (wire (pts (xy 247.65 180.975) (xy 273.05 180.975))
    (stroke (width 0) (type default))
  )
  (wire (pts (xy 109.093 104.14) (xy 116.713 104.14))
    (stroke (width 0) (type default))
  )
  (wire (pts (xy 95.123 106.68) (xy 95.123 104.14))
    (stroke (width 0) (type default))
  )
  (wire (pts (xy 266.7 86.995) (xy 273.05 86.995))
    (stroke (width 0) (type default))
  )
  (wire (pts (xy 269.24 208.915) (xy 273.05 208.915))
    (stroke (width 0) (type default))
  )
  (wire (pts (xy 112.903 127) (xy 112.903 124.46))
    (stroke (width 0) (type default))
  )
  (wire (pts (xy 157.988 117.475) (xy 155.448 117.475))
    (stroke (width 0) (type default))
  )
  (wire (pts (xy 140.97 168.91) (xy 139.065 168.91))
    (stroke (width 0) (type default))
  )
  (wire (pts (xy 180.848 127) (xy 196.723 127))
    (stroke (width 0) (type default))
  )
  (wire (pts (xy 273.05 153.035) (xy 269.24 153.035))
    (stroke (width 0) (type default))
  )
  (wire (pts (xy 171.958 144.78) (xy 179.578 144.78))
    (stroke (width 0) (type default))
  )
  (wire (pts (xy 266.7 135.255) (xy 273.05 135.255))
    (stroke (width 0) (type default))
  )
  (wire (pts (xy 267.335 201.295) (xy 271.78 201.295))
    (stroke (width 0) (type default))
  )
  (wire (pts (xy 87.503 120.65) (xy 91.313 120.65))
    (stroke (width 0) (type default))
  )
  (wire (pts (xy 266.7 104.775) (xy 273.05 104.775))
    (stroke (width 0) (type default))
  )
  (wire (pts (xy 100.838 120.65) (xy 119.253 120.65))
    (stroke (width 0) (type default))
  )
  (wire (pts (xy 266.7 84.455) (xy 273.05 84.455))
    (stroke (width 0) (type default))
  )
  (wire (pts (xy 161.798 100.965) (xy 161.798 102.87))
    (stroke (width 0) (type default))
  )
  (wire (pts (xy 100.838 116.84) (xy 100.838 118.11))
    (stroke (width 0) (type default))
  )
  (wire (pts (xy 100.838 118.11) (xy 119.253 118.11))
    (stroke (width 0) (type default))
  )
  (wire (pts (xy 184.658 100.33) (xy 184.658 102.87))
    (stroke (width 0) (type default))
  )
  (wire (pts (xy 148.463 144.78) (xy 149.733 144.78))
    (stroke (width 0) (type default))
  )
  (wire (pts (xy 266.7 97.155) (xy 273.05 97.155))
    (stroke (width 0) (type default))
  )
  (wire (pts (xy 196.723 130.81) (xy 196.723 129.54))
    (stroke (width 0) (type default))
  )
  (wire (pts (xy 116.713 114.3) (xy 119.253 114.3))
    (stroke (width 0) (type default))
  )
  (wire (pts (xy 95.123 118.11) (xy 100.838 118.11))
    (stroke (width 0) (type default))
  )
  (wire (pts (xy 140.843 129.54) (xy 161.798 129.54))
    (stroke (width 0) (type default))
  )
  (wire (pts (xy 273.05 198.755) (xy 271.78 198.755))
    (stroke (width 0) (type default))
  )
  (wire (pts (xy 161.798 129.54) (xy 184.658 129.54))
    (stroke (width 0) (type default))
  )
  (wire (pts (xy 184.658 129.54) (xy 196.723 129.54))
    (stroke (width 0) (type default))
  )
  (wire (pts (xy 140.97 168.91) (xy 153.67 168.91))
    (stroke (width 0) (type default))
  )
  (wire (pts (xy 166.243 151.13) (xy 166.243 147.32))
    (stroke (width 0) (type default))
  )
  (wire (pts (xy 180.848 102.87) (xy 180.848 100.33))
    (stroke (width 0) (type default))
  )
  (wire (pts (xy 107.188 104.14) (xy 109.093 104.14))
    (stroke (width 0) (type default))
  )
  (wire (pts (xy 266.7 147.955) (xy 273.05 147.955))
    (stroke (width 0) (type default))
  )
  (wire (pts (xy 247.65 183.515) (xy 273.05 183.515))
    (stroke (width 0) (type default))
  )
  (wire (pts (xy 161.798 117.475) (xy 161.798 120.015))
    (stroke (width 0) (type default))
  )
  (wire (pts (xy 273.05 99.695) (xy 269.24 99.695))
    (stroke (width 0) (type default))
  )
  (wire (pts (xy 138.303 144.78) (xy 148.463 144.78))
    (stroke (width 0) (type default))
  )
  (wire (pts (xy 273.05 145.415) (xy 269.24 145.415))
    (stroke (width 0) (type default))
  )
  (wire (pts (xy 184.658 100.33) (xy 180.848 100.33))
    (stroke (width 0) (type default))
  )
  (wire (pts (xy 89.408 104.14) (xy 91.313 104.14))
    (stroke (width 0) (type default))
  )
  (wire (pts (xy 157.988 127) (xy 180.848 127))
    (stroke (width 0) (type default))
  )
  (wire (pts (xy 266.7 127.635) (xy 273.05 127.635))
    (stroke (width 0) (type default))
  )
  (wire (pts (xy 271.78 196.215) (xy 273.05 196.215))
    (stroke (width 0) (type default))
  )
  (wire (pts (xy 157.988 110.49) (xy 180.848 110.49))
    (stroke (width 0) (type default))
  )
  (wire (pts (xy 266.7 163.195) (xy 273.05 163.195))
    (stroke (width 0) (type default))
  )
  (wire (pts (xy 273.05 102.235) (xy 266.7 102.235))
    (stroke (width 0) (type default))
  )
  (wire (pts (xy 269.24 208.915) (xy 269.24 212.09))
    (stroke (width 0) (type default))
  )
  (wire (pts (xy 161.798 113.03) (xy 142.113 113.03))
    (stroke (width 0) (type default))
  )
  (wire (pts (xy 149.733 147.32) (xy 148.463 147.32))
    (stroke (width 0) (type default))
  )
  (wire (pts (xy 266.7 132.715) (xy 273.05 132.715))
    (stroke (width 0) (type default))
  )
  (wire (pts (xy 161.798 117.475) (xy 157.988 117.475))
    (stroke (width 0) (type default))
  )
  (wire (pts (xy 161.798 107.95) (xy 161.798 113.03))
    (stroke (width 0) (type default))
  )
  (wire (pts (xy 140.97 171.45) (xy 140.97 168.91))
    (stroke (width 0) (type default))
  )
  (wire (pts (xy 157.988 120.015) (xy 157.988 117.475))
    (stroke (width 0) (type default))
  )
  (wire (pts (xy 161.798 113.03) (xy 184.658 113.03))
    (stroke (width 0) (type default))
  )
  (wire (pts (xy 184.658 113.03) (xy 196.723 113.03))
    (stroke (width 0) (type default))
  )
  (wire (pts (xy 269.24 107.315) (xy 269.24 114.935))
    (stroke (width 0) (type default))
  )
  (polyline (pts (xy 145.288 138.43) (xy 145.288 97.79))
    (stroke (width 0) (type default))
  )

  (wire (pts (xy 148.463 149.86) (xy 149.733 149.86))
    (stroke (width 0) (type default))
  )
  (wire (pts (xy 273.05 122.555) (xy 269.24 122.555))
    (stroke (width 0) (type default))
  )
  (wire (pts (xy 171.958 144.78) (xy 171.958 143.51))
    (stroke (width 0) (type default))
  )
  (wire (pts (xy 91.313 104.14) (xy 91.313 106.68))
    (stroke (width 0) (type default))
  )
  (wire (pts (xy 269.24 122.555) (xy 269.24 145.415))
    (stroke (width 0) (type default))
  )
  (wire (pts (xy 142.113 116.84) (xy 142.113 113.03))
    (stroke (width 0) (type default))
  )
  (wire (pts (xy 180.848 120.015) (xy 180.848 116.84))
    (stroke (width 0) (type default))
  )
  (wire (pts (xy 179.705 168.91) (xy 179.705 171.45))
    (stroke (width 0) (type default))
  )
  (wire (pts (xy 184.658 125.095) (xy 184.658 129.54))
    (stroke (width 0) (type default))
  )
  (wire (pts (xy 171.958 144.78) (xy 171.958 146.05))
    (stroke (width 0) (type default))
  )
  (wire (pts (xy 196.723 110.49) (xy 196.723 109.22))
    (stroke (width 0) (type default))
  )
  (wire (pts (xy 266.7 160.655) (xy 273.05 160.655))
    (stroke (width 0) (type default))
  )
  (wire (pts (xy 269.24 206.375) (xy 273.05 206.375))
    (stroke (width 0) (type default))
  )
  (wire (pts (xy 91.313 120.65) (xy 100.838 120.65))
    (stroke (width 0) (type default))
  )
  (wire (pts (xy 266.7 94.615) (xy 273.05 94.615))
    (stroke (width 0) (type default))
  )
  (wire (pts (xy 269.24 206.375) (xy 269.24 208.915))
    (stroke (width 0) (type default))
  )
  (wire (pts (xy 271.78 198.755) (xy 271.78 196.215))
    (stroke (width 0) (type default))
  )
  (wire (pts (xy 135.763 144.78) (xy 138.303 144.78))
    (stroke (width 0) (type default))
  )
  (wire (pts (xy 148.463 151.13) (xy 148.463 149.86))
    (stroke (width 0) (type default))
  )
  (wire (pts (xy 247.65 178.435) (xy 273.05 178.435))
    (stroke (width 0) (type default))
  )
  (wire (pts (xy 269.24 99.695) (xy 269.24 107.315))
    (stroke (width 0) (type default))
  )
  (wire (pts (xy 164.973 144.78) (xy 171.958 144.78))
    (stroke (width 0) (type default))
  )
  (wire (pts (xy 112.903 124.46) (xy 119.253 124.46))
    (stroke (width 0) (type default))
  )
  (wire (pts (xy 140.843 114.3) (xy 140.843 110.49))
    (stroke (width 0) (type default))
  )
  (wire (pts (xy 196.723 125.73) (xy 196.723 127))
    (stroke (width 0) (type default))
  )
  (wire (pts (xy 116.713 104.14) (xy 116.713 114.3))
    (stroke (width 0) (type default))
  )
  (wire (pts (xy 273.05 203.835) (xy 271.78 203.835))
    (stroke (width 0) (type default))
  )
  (polyline (pts (xy 145.288 97.79) (xy 170.053 97.79))
    (stroke (width 0) (type default))
  )
  (polyline (pts (xy 189.738 138.43) (xy 189.738 158.115))
    (stroke (width 0) (type default))
  )

  (wire (pts (xy 157.988 100.965) (xy 156.083 100.965))
    (stroke (width 0) (type default))
  )
  (wire (pts (xy 161.798 125.095) (xy 161.798 129.54))
    (stroke (width 0) (type default))
  )
  (wire (pts (xy 269.24 114.935) (xy 269.24 122.555))
    (stroke (width 0) (type default))
  )
  (wire (pts (xy 184.658 107.95) (xy 184.658 113.03))
    (stroke (width 0) (type default))
  )
  (polyline (pts (xy 189.738 158.115) (xy 125.603 158.115))
    (stroke (width 0) (type default))
  )

  (wire (pts (xy 273.05 114.935) (xy 269.24 114.935))
    (stroke (width 0) (type default))
  )
  (wire (pts (xy 167.005 168.91) (xy 164.465 168.91))
    (stroke (width 0) (type default))
  )
  (wire (pts (xy 271.78 201.295) (xy 273.05 201.295))
    (stroke (width 0) (type default))
  )
  (wire (pts (xy 269.24 145.415) (xy 269.24 153.035))
    (stroke (width 0) (type default))
  )
  (wire (pts (xy 266.7 137.795) (xy 273.05 137.795))
    (stroke (width 0) (type default))
  )
  (polyline (pts (xy 170.053 97.79) (xy 170.053 138.43))
    (stroke (width 0) (type default))
  )

  (wire (pts (xy 139.573 121.92) (xy 142.113 121.92))
    (stroke (width 0) (type default))
  )
  (wire (pts (xy 273.05 92.075) (xy 266.7 92.075))
    (stroke (width 0) (type default))
  )
  (wire (pts (xy 167.005 168.91) (xy 179.705 168.91))
    (stroke (width 0) (type default))
  )
  (wire (pts (xy 180.848 110.49) (xy 196.723 110.49))
    (stroke (width 0) (type default))
  )
  (polyline (pts (xy 125.603 158.115) (xy 125.603 138.43))
    (stroke (width 0) (type default))
  )

  (wire (pts (xy 142.113 127) (xy 157.988 127))
    (stroke (width 0) (type default))
  )
  (wire (pts (xy 184.658 116.84) (xy 180.848 116.84))
    (stroke (width 0) (type default))
  )
  (wire (pts (xy 266.7 142.875) (xy 273.05 142.875))
    (stroke (width 0) (type default))
  )
  (wire (pts (xy 161.798 100.965) (xy 157.988 100.965))
    (stroke (width 0) (type default))
  )
  (wire (pts (xy 91.313 104.14) (xy 95.123 104.14))
    (stroke (width 0) (type default))
  )
  (wire (pts (xy 266.7 150.495) (xy 273.05 150.495))
    (stroke (width 0) (type default))
  )
  (wire (pts (xy 139.573 124.46) (xy 140.843 124.46))
    (stroke (width 0) (type default))
  )
  (wire (pts (xy 140.843 124.46) (xy 140.843 129.54))
    (stroke (width 0) (type default))
  )
  (wire (pts (xy 153.67 168.91) (xy 153.67 171.45))
    (stroke (width 0) (type default))
  )
  (wire (pts (xy 100.838 121.92) (xy 100.838 120.65))
    (stroke (width 0) (type default))
  )
  (wire (pts (xy 157.988 102.87) (xy 157.988 100.965))
    (stroke (width 0) (type default))
  )
  (wire (pts (xy 273.05 89.535) (xy 266.7 89.535))
    (stroke (width 0) (type default))
  )
  (polyline (pts (xy 170.053 138.43) (xy 189.738 138.43))
    (stroke (width 0) (type default))
  )

  (wire (pts (xy 157.988 125.095) (xy 157.988 127))
    (stroke (width 0) (type default))
  )
  (wire (pts (xy 148.463 147.32) (xy 148.463 144.78))
    (stroke (width 0) (type default))
  )
  (wire (pts (xy 95.123 118.11) (xy 95.123 111.76))
    (stroke (width 0) (type default))
  )
  (wire (pts (xy 180.848 116.84) (xy 179.578 116.84))
    (stroke (width 0) (type default))
  )
  (wire (pts (xy 184.658 116.84) (xy 184.658 120.015))
    (stroke (width 0) (type default))
  )
  (wire (pts (xy 166.243 147.32) (xy 164.973 147.32))
    (stroke (width 0) (type default))
  )
  (wire (pts (xy 273.05 107.315) (xy 269.24 107.315))
    (stroke (width 0) (type default))
  )
  (wire (pts (xy 180.848 100.33) (xy 179.578 100.33))
    (stroke (width 0) (type default))
  )
  (wire (pts (xy 142.113 121.92) (xy 142.113 127))
    (stroke (width 0) (type default))
  )
  (wire (pts (xy 196.723 129.54) (xy 219.075 129.54))
    (stroke (width 0) (type default))
  )
  (wire (pts (xy 271.78 203.835) (xy 271.78 201.295))
    (stroke (width 0) (type default))
  )
  (wire (pts (xy 266.7 158.115) (xy 273.05 158.115))
    (stroke (width 0) (type default))
  )
  (wire (pts (xy 266.7 130.175) (xy 273.05 130.175))
    (stroke (width 0) (type default))
  )
  (wire (pts (xy 196.723 113.03) (xy 219.075 113.03))
    (stroke (width 0) (type default))
  )
  (wire (pts (xy 87.503 118.11) (xy 95.123 118.11))
    (stroke (width 0) (type default))
  )
  (wire (pts (xy 196.723 113.03) (xy 196.723 114.3))
    (stroke (width 0) (type default))
  )
  (wire (pts (xy 266.7 81.915) (xy 273.05 81.915))
    (stroke (width 0) (type default))
  )
  (wire (pts (xy 142.113 116.84) (xy 139.573 116.84))
    (stroke (width 0) (type default))
  )
  (wire (pts (xy 267.97 196.215) (xy 271.78 196.215))
    (stroke (width 0) (type default))
  )
  (wire (pts (xy 266.7 140.335) (xy 273.05 140.335))
    (stroke (width 0) (type default))
  )
  (wire (pts (xy 180.848 125.095) (xy 180.848 127))
    (stroke (width 0) (type default))
  )
  (wire (pts (xy 157.988 107.95) (xy 157.988 110.49))
    (stroke (width 0) (type default))
  )
  (wire (pts (xy 196.723 110.49) (xy 219.075 110.49))
    (stroke (width 0) (type default))
  )
  (wire (pts (xy 196.723 127) (xy 219.075 127))
    (stroke (width 0) (type default))
  )
  (wire (pts (xy 91.313 111.76) (xy 91.313 120.65))
    (stroke (width 0) (type default))
  )
  (wire (pts (xy 180.848 107.95) (xy 180.848 110.49))
    (stroke (width 0) (type default))
  )
  (wire (pts (xy 140.843 110.49) (xy 157.988 110.49))
    (stroke (width 0) (type default))
  )
  (wire (pts (xy 266.7 79.375) (xy 273.05 79.375))
    (stroke (width 0) (type default))
  )
  (wire (pts (xy 269.24 153.035) (xy 269.24 206.375))
    (stroke (width 0) (type default))
  )
  (wire (pts (xy 139.573 114.3) (xy 140.843 114.3))
    (stroke (width 0) (type default))
  )
  (wire (pts (xy 167.005 171.45) (xy 167.005 168.91))
    (stroke (width 0) (type default))
  )
  (wire (pts (xy 247.65 175.895) (xy 273.05 175.895))
    (stroke (width 0) (type default))
  )
  (wire (pts (xy 109.093 106.68) (xy 109.093 104.14))
    (stroke (width 0) (type default))
  )
  (polyline (pts (xy 125.603 138.43) (xy 145.288 138.43))
    (stroke (width 0) (type default))
  )

  (text "DNP" (at 145.415 97.79 0)
    (effects (font (size 1.27 1.27)) (justify left bottom))
  )
  (text "Camera interface" (at 165.735 80.01 0)
    (effects (font (size 2.54 2.54) (thickness 0.508) bold) (justify left bottom))
  )

  (label "CCI1_I2C_SCL_3V3" (at 247.65 183.515 0) (fields_autoplaced)
    (effects (font (size 1.27 1.27)) (justify left bottom))
  )
  (label "CCI0_I2C_SCL_3V3" (at 219.075 110.49 180) (fields_autoplaced)
    (effects (font (size 1.27 1.27)) (justify right bottom))
  )
  (label "CCI1_I2C_SDA_3V3" (at 219.075 129.54 180) (fields_autoplaced)
    (effects (font (size 1.27 1.27)) (justify right bottom))
  )
  (label "CCI1_I2C_SDA_3V3" (at 247.65 180.975 0) (fields_autoplaced)
    (effects (font (size 1.27 1.27)) (justify left bottom))
  )
  (label "CCI1_I2C_SCL_3V3" (at 219.075 127 180) (fields_autoplaced)
    (effects (font (size 1.27 1.27)) (justify right bottom))
  )
  (label "CCI0_I2C_SDA_3V3" (at 219.075 113.03 180) (fields_autoplaced)
    (effects (font (size 1.27 1.27)) (justify right bottom))
  )
  (label "CCI0_I2C_SDA_3V3" (at 247.65 175.895 0) (fields_autoplaced)
    (effects (font (size 1.27 1.27)) (justify left bottom))
  )
  (label "CCI0_I2C_SCL_3V3" (at 247.65 178.435 0) (fields_autoplaced)
    (effects (font (size 1.27 1.27)) (justify left bottom))
  )

  (global_label "PL_1V8" (shape input) (at 179.578 144.78 0) (fields_autoplaced)
    (effects (font (size 1.27 1.27)) (justify left))
    (property "Intersheetrefs" "${INTERSHEET_REFS}" (at 66.548 -5.08 0)
      (effects (font (size 1.27 1.27)) hide)
    )
  )
  (global_label "PL_3V3" (shape input) (at 179.578 100.33 180) (fields_autoplaced)
    (effects (font (size 1.27 1.27)) (justify right))
    (property "Intersheetrefs" "${INTERSHEET_REFS}" (at 305.308 204.47 0)
      (effects (font (size 1.27 1.27)) hide)
    )
  )
  (global_label "PL_3V3" (shape input) (at 179.578 116.84 180) (fields_autoplaced)
    (effects (font (size 1.27 1.27)) (justify right))
    (property "Intersheetrefs" "${INTERSHEET_REFS}" (at 305.308 237.49 0)
      (effects (font (size 1.27 1.27)) hide)
    )
  )
  (global_label "SOM_5V0" (shape input) (at 267.335 201.295 180) (fields_autoplaced)
    (effects (font (size 1.27 1.27)) (justify right))
    (property "Intersheetrefs" "${INTERSHEET_REFS}" (at 57.15 56.515 0)
      (effects (font (size 1.27 1.27)) hide)
    )
  )
  (global_label "PL_3V3" (shape input) (at 107.188 104.14 180) (fields_autoplaced)
    (effects (font (size 1.27 1.27)) (justify right))
    (property "Intersheetrefs" "${INTERSHEET_REFS}" (at 56.388 0 0)
      (effects (font (size 1.27 1.27)) hide)
    )
  )
  (global_label "PL_3V3" (shape input) (at 89.408 104.14 180) (fields_autoplaced)
    (effects (font (size 1.27 1.27)) (justify right))
    (property "Intersheetrefs" "${INTERSHEET_REFS}" (at 56.388 0 0)
      (effects (font (size 1.27 1.27)) hide)
    )
  )
  (global_label "PL_3V3" (shape input) (at 164.465 168.91 180) (fields_autoplaced)
    (effects (font (size 1.27 1.27)) (justify right))
    (property "Intersheetrefs" "${INTERSHEET_REFS}" (at -46.355 29.21 0)
      (effects (font (size 1.27 1.27)) hide)
    )
  )
  (global_label "SOM_5V0" (shape input) (at 139.065 168.91 180) (fields_autoplaced)
    (effects (font (size 1.27 1.27)) (justify right))
    (property "Intersheetrefs" "${INTERSHEET_REFS}" (at -71.12 24.13 0)
      (effects (font (size 1.27 1.27)) hide)
    )
  )
  (global_label "PL_3V3" (shape input) (at 135.763 144.78 180) (fields_autoplaced)
    (effects (font (size 1.27 1.27)) (justify right))
    (property "Intersheetrefs" "${INTERSHEET_REFS}" (at 73.533 -5.08 0)
      (effects (font (size 1.27 1.27)) hide)
    )
  )
  (global_label "PL_3V3" (shape input) (at 267.97 196.215 180) (fields_autoplaced)
    (effects (font (size 1.27 1.27)) (justify right))
    (property "Intersheetrefs" "${INTERSHEET_REFS}" (at 57.15 56.515 0)
      (effects (font (size 1.27 1.27)) hide)
    )
  )
  (global_label "PL_1V8" (shape input) (at 156.083 100.965 180) (fields_autoplaced)
    (effects (font (size 1.27 1.27)) (justify right))
    (property "Intersheetrefs" "${INTERSHEET_REFS}" (at 257.683 205.105 0)
      (effects (font (size 1.27 1.27)) hide)
    )
  )
  (global_label "PL_1V8" (shape input) (at 155.448 117.475 180) (fields_autoplaced)
    (effects (font (size 1.27 1.27)) (justify right))
    (property "Intersheetrefs" "${INTERSHEET_REFS}" (at 255.778 238.125 0)
      (effects (font (size 1.27 1.27)) hide)
    )
  )

  (hierarchical_label "HPA05_CC_P" (shape input) (at 266.7 150.495 180) (fields_autoplaced)
    (effects (font (size 1.27 1.27)) (justify right))
  )
  (hierarchical_label "HPA08_N" (shape input) (at 266.7 130.175 180) (fields_autoplaced)
    (effects (font (size 1.27 1.27)) (justify right))
  )
  (hierarchical_label "HPA09_N" (shape input) (at 266.7 125.095 180) (fields_autoplaced)
    (effects (font (size 1.27 1.27)) (justify right))
  )
  (hierarchical_label "HPA07_P" (shape input) (at 266.7 137.795 180) (fields_autoplaced)
    (effects (font (size 1.27 1.27)) (justify right))
  )
  (hierarchical_label "CAM0_RST" (shape input) (at 266.7 160.655 180) (fields_autoplaced)
    (effects (font (size 1.27 1.27)) (justify right))
  )
  (hierarchical_label "HDA01" (shape input) (at 87.503 120.65 180) (fields_autoplaced)
    (effects (font (size 1.27 1.27)) (justify right))
  )
  (hierarchical_label "HPA00_CC_P" (shape input) (at 266.7 104.775 180) (fields_autoplaced)
    (effects (font (size 1.27 1.27)) (justify right))
  )
  (hierarchical_label "HPA06_P" (shape input) (at 266.7 142.875 180) (fields_autoplaced)
    (effects (font (size 1.27 1.27)) (justify right))
  )
  (hierarchical_label "HPA01_P" (shape input) (at 266.7 97.155 180) (fields_autoplaced)
    (effects (font (size 1.27 1.27)) (justify right))
  )
  (hierarchical_label "HDA00_CC" (shape input) (at 87.503 118.11 180) (fields_autoplaced)
    (effects (font (size 1.27 1.27)) (justify right))
  )
  (hierarchical_label "HPA05_CC_N" (shape input) (at 266.7 147.955 180) (fields_autoplaced)
    (effects (font (size 1.27 1.27)) (justify right))
  )
  (hierarchical_label "HPA07_N" (shape input) (at 266.7 135.255 180) (fields_autoplaced)
    (effects (font (size 1.27 1.27)) (justify right))
  )
  (hierarchical_label "HPA01_N" (shape input) (at 266.7 94.615 180) (fields_autoplaced)
    (effects (font (size 1.27 1.27)) (justify right))
  )
  (hierarchical_label "HPA00_CC_N" (shape input) (at 266.7 102.235 180) (fields_autoplaced)
    (effects (font (size 1.27 1.27)) (justify right))
  )
  (hierarchical_label "HPA09_P" (shape input) (at 266.7 127.635 180) (fields_autoplaced)
    (effects (font (size 1.27 1.27)) (justify right))
  )
  (hierarchical_label "HPA02_N" (shape input) (at 266.7 89.535 180) (fields_autoplaced)
    (effects (font (size 1.27 1.27)) (justify right))
  )
  (hierarchical_label "HPA04_P" (shape input) (at 266.7 81.915 180) (fields_autoplaced)
    (effects (font (size 1.27 1.27)) (justify right))
  )
  (hierarchical_label "HPA04_N" (shape input) (at 266.7 79.375 180) (fields_autoplaced)
    (effects (font (size 1.27 1.27)) (justify right))
  )
  (hierarchical_label "HPA03_N" (shape input) (at 266.7 84.455 180) (fields_autoplaced)
    (effects (font (size 1.27 1.27)) (justify right))
  )
  (hierarchical_label "HPA03_P" (shape input) (at 266.7 86.995 180) (fields_autoplaced)
    (effects (font (size 1.27 1.27)) (justify right))
  )
  (hierarchical_label "CAM1_VSYNC" (shape input) (at 266.7 163.195 180) (fields_autoplaced)
    (effects (font (size 1.27 1.27)) (justify right))
  )
  (hierarchical_label "HPA08_P" (shape input) (at 266.7 132.715 180) (fields_autoplaced)
    (effects (font (size 1.27 1.27)) (justify right))
  )
  (hierarchical_label "HPA02_P" (shape input) (at 266.7 92.075 180) (fields_autoplaced)
    (effects (font (size 1.27 1.27)) (justify right))
  )
  (hierarchical_label "HPA06_N" (shape input) (at 266.7 140.335 180) (fields_autoplaced)
    (effects (font (size 1.27 1.27)) (justify right))
  )
  (hierarchical_label "CAM0_VSYNC" (shape input) (at 266.7 158.115 180) (fields_autoplaced)
    (effects (font (size 1.27 1.27)) (justify right))
  )

  (symbol (lib_id "kria-k26-devboard:Conn_FFC_WE_68715014522_CUSTOM_TWO-SIDES") (at 273.05 79.375 0) (unit 1)
    (in_bom yes) (on_board yes) (dnp no) (fields_autoplaced)
    (property "Reference" "J3" (at 281.94 143.51 0)
      (effects (font (size 1.27 1.27)) (justify left))
    )
    (property "Value" "Conn_FFC_WE_68715014522_CUSTOM_TWO-SIDES" (at 281.94 146.05 0)
      (effects (font (size 1.27 1.27) (thickness 0.15)) (justify left bottom))
    )
    (property "Footprint" "kria-k26-devboard-footprints:Conn_FFC_WE_68715014x22_ALT" (at 292.1 86.995 0)
      (effects (font (size 1.27 1.27) (thickness 0.15)) (justify left bottom) hide)
    )
    (property "Datasheet" "https://www.we-online.com/components/products/datasheet/68715014522.pdf" (at 292.1 89.535 0)
      (effects (font (size 1.27 1.27) (thickness 0.15)) (justify left bottom) hide)
    )
    (property "MPN" "68715014522" (at 281.94 146.05 0)
      (effects (font (size 1.27 1.27) (thickness 0.15)) (justify left bottom) hide)
    )
    (property "Manufacturer" "Würth Elektronik" (at 292.1 94.615 0)
      (effects (font (size 1.27 1.27) (thickness 0.15)) (justify left bottom) hide)
    )
    (property "Author" "Antmicro" (at 292.1 97.155 0)
      (effects (font (size 1.27 1.27) (thickness 0.15)) (justify left bottom) hide)
    )
    (property "License" "Apache-2.0" (at 292.1 99.695 0)
      (effects (font (size 1.27 1.27) (thickness 0.15)) (justify left bottom) hide)
    )
    (property "VSD_Class" "Antmicro Dual Camera interface" (at 292.1 102.235 0)
      (effects (font (size 1.27 1.27)) (justify left bottom) hide)
    )
    (pin "1")
    (pin "10")
    (pin "11")
    (pin "12")
    (pin "13")
    (pin "14")
    (pin "15")
    (pin "16")
    (pin "17")
    (pin "18")
    (pin "19")
    (pin "2")
    (pin "20")
    (pin "21")
    (pin "22")
    (pin "23")
    (pin "24")
    (pin "25")
    (pin "26")
    (pin "27")
    (pin "28")
    (pin "29")
    (pin "3")
    (pin "30")
    (pin "31")
    (pin "32")
    (pin "33")
    (pin "34")
    (pin "35")
    (pin "36")
    (pin "37")
    (pin "38")
    (pin "39")
    (pin "4")
    (pin "40")
    (pin "41")
    (pin "42")
    (pin "43")
    (pin "44")
    (pin "45")
    (pin "46")
    (pin "47")
    (pin "48")
    (pin "49")
    (pin "5")
    (pin "50")
    (pin "6")
    (pin "7")
    (pin "8")
    (pin "9")
    (pin "MP1")
    (pin "MP2")
    (instances
      (project "kria-k26-devboard"
        (path ""
          (reference "J3") (unit 1)
        )
      )
    )
  )

  (symbol (lib_id "kria-k26-devboard:R_1k5_0402") (at 161.798 102.87 270) (unit 1)
    (in_bom no) (on_board yes) (dnp yes)
    (property "Reference" "R28" (at 163.703 104.14 90)
      (effects (font (size 1.524 1.524)) (justify left))
    )
    (property "Value" "R_1k5_0402" (at 157.988 102.87 0)
      (effects (font (size 1.27 1.27) (thickness 0.15)) (justify left bottom) hide)
    )
    (property "Footprint" "kria-k26-devboard-footprints:R_0402_1005Metric" (at 166.878 107.95 0)
      (effects (font (size 1.27 1.27) (thickness 0.15)) (justify left bottom) hide)
    )
    (property "Datasheet" "https://www.bourns.com/docs/product-datasheets/cr.pdf" (at 161.798 102.87 0)
      (effects (font (size 1.27 1.27) (thickness 0.15)) (justify left bottom) hide)
    )
    (property "Manufacturer" "Bourns" (at 171.958 107.95 0)
      (effects (font (size 1.27 1.27) (thickness 0.15)) (justify left bottom) hide)
    )
    (property "MPN" "CR0402-FX-1501GLF" (at 169.418 107.95 0)
      (effects (font (size 1.27 1.27) (thickness 0.15)) (justify left bottom) hide)
    )
    (property "Val" "1k5" (at 163.703 106.68 90)
      (effects (font (size 1.27 1.27) (thickness 0.15)) (justify left))
    )
    (property "DNP" "DNP" (at 161.798 103.505 0)
      (effects (font (size 1.27 1.27)) (justify left))
    )
    (property "License" "Apache-2.0" (at 136.398 123.19 0)
      (effects (font (size 1.27 1.27) (thickness 0.15)) (justify left bottom) hide)
    )
    (property "Author" "Antmicro" (at 133.858 123.19 0)
      (effects (font (size 1.27 1.27) (thickness 0.15)) (justify left bottom) hide)
    )
    (property "Tolerance" "1%" (at 151.638 123.19 0)
      (effects (font (size 1.27 1.27)) (justify left bottom) hide)
    )
    (pin "1")
    (pin "2")
    (instances
      (project "kria-k26-devboard"
        (path ""
          (reference "R28") (unit 1)
        )
      )
    )
  )

  (symbol (lib_id "kria-k26-devboard:R_1k5_0402") (at 157.988 102.87 270) (unit 1)
    (in_bom no) (on_board yes) (dnp yes)
    (property "Reference" "R26" (at 156.083 104.14 90)
      (effects (font (size 1.524 1.524)) (justify right))
    )
    (property "Value" "R_1k5_0402" (at 154.178 102.87 0)
      (effects (font (size 1.27 1.27) (thickness 0.15)) (justify left bottom) hide)
    )
    (property "Footprint" "kria-k26-devboard-footprints:R_0402_1005Metric" (at 163.068 107.95 0)
      (effects (font (size 1.27 1.27) (thickness 0.15)) (justify left bottom) hide)
    )
    (property "Datasheet" "https://www.bourns.com/docs/product-datasheets/cr.pdf" (at 157.988 102.87 0)
      (effects (font (size 1.27 1.27) (thickness 0.15)) (justify left bottom) hide)
    )
    (property "Manufacturer" "Bourns" (at 168.148 107.95 0)
      (effects (font (size 1.27 1.27) (thickness 0.15)) (justify left bottom) hide)
    )
    (property "MPN" "CR0402-FX-1501GLF" (at 165.608 107.95 0)
      (effects (font (size 1.27 1.27) (thickness 0.15)) (justify left bottom) hide)
    )
    (property "Val" "1k5" (at 156.083 106.68 90)
      (effects (font (size 1.27 1.27) (thickness 0.15)) (justify right))
    )
    (property "DNP" "DNP" (at 157.988 107.315 0)
      (effects (font (size 1.27 1.27)) (justify right))
    )
    (property "License" "Apache-2.0" (at 132.588 123.19 0)
      (effects (font (size 1.27 1.27) (thickness 0.15)) (justify left bottom) hide)
    )
    (property "Author" "Antmicro" (at 130.048 123.19 0)
      (effects (font (size 1.27 1.27) (thickness 0.15)) (justify left bottom) hide)
    )
    (property "Tolerance" "1%" (at 147.828 123.19 0)
      (effects (font (size 1.27 1.27)) (justify left bottom) hide)
    )
    (pin "1")
    (pin "2")
    (instances
      (project "kria-k26-devboard"
        (path ""
          (reference "R26") (unit 1)
        )
      )
    )
  )

  (symbol (lib_id "kria-k26-devboard:R_1k5_0402") (at 161.798 120.015 270) (unit 1)
    (in_bom no) (on_board yes) (dnp yes)
    (property "Reference" "R27" (at 163.703 120.65 90)
      (effects (font (size 1.524 1.524)) (justify left))
    )
    (property "Value" "R_1k5_0402" (at 157.988 120.015 0)
      (effects (font (size 1.27 1.27) (thickness 0.15)) (justify left bottom) hide)
    )
    (property "Footprint" "kria-k26-devboard-footprints:R_0402_1005Metric" (at 166.878 125.095 0)
      (effects (font (size 1.27 1.27) (thickness 0.15)) (justify left bottom) hide)
    )
    (property "Datasheet" "https://www.bourns.com/docs/product-datasheets/cr.pdf" (at 161.798 120.015 0)
      (effects (font (size 1.27 1.27) (thickness 0.15)) (justify left bottom) hide)
    )
    (property "Manufacturer" "Bourns" (at 171.958 125.095 0)
      (effects (font (size 1.27 1.27) (thickness 0.15)) (justify left bottom) hide)
    )
    (property "MPN" "CR0402-FX-1501GLF" (at 169.418 125.095 0)
      (effects (font (size 1.27 1.27) (thickness 0.15)) (justify left bottom) hide)
    )
    (property "Val" "1k5" (at 163.703 123.19 90)
      (effects (font (size 1.27 1.27) (thickness 0.15)) (justify left))
    )
    (property "DNP" "DNP" (at 161.798 120.65 0)
      (effects (font (size 1.27 1.27)) (justify left))
    )
    (property "License" "Apache-2.0" (at 136.398 140.335 0)
      (effects (font (size 1.27 1.27) (thickness 0.15)) (justify left bottom) hide)
    )
    (property "Author" "Antmicro" (at 133.858 140.335 0)
      (effects (font (size 1.27 1.27) (thickness 0.15)) (justify left bottom) hide)
    )
    (property "Tolerance" "1%" (at 151.638 140.335 0)
      (effects (font (size 1.27 1.27)) (justify left bottom) hide)
    )
    (pin "1")
    (pin "2")
    (instances
      (project "kria-k26-devboard"
        (path ""
          (reference "R27") (unit 1)
        )
      )
    )
  )

  (symbol (lib_id "kria-k26-devboard:R_1k5_0402") (at 157.988 120.015 270) (unit 1)
    (in_bom no) (on_board yes) (dnp yes)
    (property "Reference" "R25" (at 156.083 120.65 90)
      (effects (font (size 1.524 1.524)) (justify right))
    )
    (property "Value" "R_1k5_0402" (at 154.178 120.015 0)
      (effects (font (size 1.27 1.27) (thickness 0.15)) (justify left bottom) hide)
    )
    (property "Footprint" "kria-k26-devboard-footprints:R_0402_1005Metric" (at 163.068 125.095 0)
      (effects (font (size 1.27 1.27) (thickness 0.15)) (justify left bottom) hide)
    )
    (property "Datasheet" "https://www.bourns.com/docs/product-datasheets/cr.pdf" (at 157.988 120.015 0)
      (effects (font (size 1.27 1.27) (thickness 0.15)) (justify left bottom) hide)
    )
    (property "Manufacturer" "Bourns" (at 168.148 125.095 0)
      (effects (font (size 1.27 1.27) (thickness 0.15)) (justify left bottom) hide)
    )
    (property "MPN" "CR0402-FX-1501GLF" (at 165.608 125.095 0)
      (effects (font (size 1.27 1.27) (thickness 0.15)) (justify left bottom) hide)
    )
    (property "Val" "1k5" (at 156.083 123.19 90)
      (effects (font (size 1.27 1.27) (thickness 0.15)) (justify right))
    )
    (property "DNP" "DNP" (at 157.988 124.46 0)
      (effects (font (size 1.27 1.27)) (justify right))
    )
    (property "License" "Apache-2.0" (at 132.588 140.335 0)
      (effects (font (size 1.27 1.27) (thickness 0.15)) (justify left bottom) hide)
    )
    (property "Author" "Antmicro" (at 130.048 140.335 0)
      (effects (font (size 1.27 1.27) (thickness 0.15)) (justify left bottom) hide)
    )
    (property "Tolerance" "1%" (at 147.828 140.335 0)
      (effects (font (size 1.27 1.27)) (justify left bottom) hide)
    )
    (pin "1")
    (pin "2")
    (instances
      (project "kria-k26-devboard"
        (path ""
          (reference "R25") (unit 1)
        )
      )
    )
  )

  (symbol (lib_id "kria-k26-devboard:AP7340-18FS4-7") (at 149.733 144.78 0) (unit 1)
    (in_bom yes) (on_board yes) (dnp yes)
    (property "Reference" "U11" (at 157.353 135.89 0)
      (effects (font (size 1.27 1.27)))
    )
    (property "Value" "AP7340-18FS4-7" (at 157.353 138.43 0)
      (effects (font (size 1.27 1.27) (thickness 0.15)) (justify left bottom))
    )
    (property "Footprint" "kria-k26-devboard-footprints:XDFN4" (at 138.303 161.29 0)
      (effects (font (size 1.27 1.27) (thickness 0.15)) (justify left bottom) hide)
    )
    (property "Datasheet" "https://www.diodes.com/assets/Datasheets/AP7340.pdf" (at 149.733 144.78 0)
      (effects (font (size 1.27 1.27) (thickness 0.15)) (justify left bottom) hide)
    )
    (property "MPN" "AP7340-18FS4-7" (at 147.193 158.75 0)
      (effects (font (size 1.27 1.27) (thickness 0.15)) (justify left bottom) hide)
    )
    (property "Manufacturer" "Diodes Incorporated" (at 148.463 156.21 0)
      (effects (font (size 1.27 1.27) (thickness 0.15)) (justify left bottom) hide)
    )
    (property "Author" "Antmicro" (at 178.943 162.56 0)
      (effects (font (size 1.27 1.27) (thickness 0.15)) (justify left bottom) hide)
    )
    (property "License" "Apache-2.0" (at 178.943 165.1 0)
      (effects (font (size 1.27 1.27) (thickness 0.15)) (justify left bottom) hide)
    )
    (pin "1")
    (pin "2")
    (pin "3")
    (pin "4")
    (pin "5")
    (instances
      (project "kria-k26-devboard"
        (path ""
          (reference "U11") (unit 1)
        )
      )
    )
  )

  (symbol (lib_id "kria-k26-devboard:C_470n_0402") (at 138.303 146.05 270) (unit 1)
    (in_bom no) (on_board yes) (dnp yes) (fields_autoplaced)
    (property "Reference" "C30" (at 140.843 146.0563 90)
      (effects (font (size 1.524 1.524)) (justify left))
    )
    (property "Value" "C_470n_0402" (at 134.493 146.05 0)
      (effects (font (size 1.27 1.27) (thickness 0.15)) (justify left bottom) hide)
    )
    (property "Footprint" "kria-k26-devboard-footprints:C_0402_1005Metric" (at 143.383 151.13 0)
      (effects (font (size 1.27 1.27) (thickness 0.15)) (justify left bottom) hide)
    )
    (property "Datasheet" " " (at 138.303 146.05 0)
      (effects (font (size 1.27 1.27) (thickness 0.15)) (justify left bottom) hide)
    )
    (property "Manufacturer" "TDK" (at 148.463 151.13 0)
      (effects (font (size 1.27 1.27) (thickness 0.15)) (justify left bottom) hide)
    )
    (property "MPN" "C1005X5R1E474M050BB" (at 145.923 151.13 0)
      (effects (font (size 1.27 1.27) (thickness 0.15)) (justify left bottom) hide)
    )
    (property "Val" "470n" (at 140.843 149.2312 90)
      (effects (font (size 1.27 1.27) (thickness 0.15)) (justify left))
    )
    (property "DNP" "DNP" (at 140.843 151.7712 90)
      (effects (font (size 1.27 1.27)) (justify left))
    )
    (property "License" "Apache-2.0" (at 115.443 166.37 0)
      (effects (font (size 1.27 1.27) (thickness 0.15)) (justify left bottom) hide)
    )
    (property "Author" "Antmicro" (at 112.903 166.37 0)
      (effects (font (size 1.27 1.27) (thickness 0.15)) (justify left bottom) hide)
    )
    (property "Voltage" "" (at 110.363 166.37 0)
      (effects (font (size 1.27 1.27)) (justify left bottom) hide)
    )
    (property "Dielectric" "" (at 107.823 166.37 0)
      (effects (font (size 1.27 1.27)) (justify left bottom) hide)
    )
    (pin "1")
    (pin "2")
    (instances
      (project "kria-k26-devboard"
        (path ""
          (reference "C30") (unit 1)
        )
      )
    )
  )

  (symbol (lib_id "kria-k26-devboard:C_470n_0402") (at 171.958 146.05 270) (unit 1)
    (in_bom no) (on_board yes) (dnp yes) (fields_autoplaced)
    (property "Reference" "C31" (at 174.498 146.0563 90)
      (effects (font (size 1.524 1.524)) (justify left))
    )
    (property "Value" "C_470n_0402" (at 168.148 146.05 0)
      (effects (font (size 1.27 1.27) (thickness 0.15)) (justify left bottom) hide)
    )
    (property "Footprint" "kria-k26-devboard-footprints:C_0402_1005Metric" (at 177.038 151.13 0)
      (effects (font (size 1.27 1.27) (thickness 0.15)) (justify left bottom) hide)
    )
    (property "Datasheet" " " (at 171.958 146.05 0)
      (effects (font (size 1.27 1.27) (thickness 0.15)) (justify left bottom) hide)
    )
    (property "Manufacturer" "TDK" (at 182.118 151.13 0)
      (effects (font (size 1.27 1.27) (thickness 0.15)) (justify left bottom) hide)
    )
    (property "MPN" "C1005X5R1E474M050BB" (at 179.578 151.13 0)
      (effects (font (size 1.27 1.27) (thickness 0.15)) (justify left bottom) hide)
    )
    (property "Val" "470n" (at 174.498 149.2312 90)
      (effects (font (size 1.27 1.27) (thickness 0.15)) (justify left))
    )
    (property "DNP" "DNP" (at 174.498 151.7712 90)
      (effects (font (size 1.27 1.27)) (justify left))
    )
    (property "License" "Apache-2.0" (at 149.098 166.37 0)
      (effects (font (size 1.27 1.27) (thickness 0.15)) (justify left bottom) hide)
    )
    (property "Author" "Antmicro" (at 146.558 166.37 0)
      (effects (font (size 1.27 1.27) (thickness 0.15)) (justify left bottom) hide)
    )
    (property "Voltage" "" (at 144.018 166.37 0)
      (effects (font (size 1.27 1.27)) (justify left bottom) hide)
    )
    (property "Dielectric" "" (at 141.478 166.37 0)
      (effects (font (size 1.27 1.27)) (justify left bottom) hide)
    )
    (pin "1")
    (pin "2")
    (instances
      (project "kria-k26-devboard"
        (path ""
          (reference "C31") (unit 1)
        )
      )
    )
  )

  (symbol (lib_id "kria-k26-devboard:GND") (at 138.303 151.13 0) (unit 1)
    (in_bom yes) (on_board yes) (dnp no) (fields_autoplaced)
    (property "Reference" "#PWR053" (at 138.303 157.48 0)
      (effects (font (size 1.27 1.27)) hide)
    )
    (property "Value" "GND" (at 138.303 156.21 0)
      (effects (font (size 1.27 1.27)))
    )
    (property "Footprint" "" (at 147.193 158.75 0)
      (effects (font (size 1.27 1.27) (thickness 0.15)) (justify left bottom) hide)
    )
    (property "Datasheet" "" (at 147.193 163.83 0)
      (effects (font (size 1.27 1.27) (thickness 0.15)) (justify left bottom) hide)
    )
    (property "Author" "Antmicro" (at 147.193 158.75 0)
      (effects (font (size 1.27 1.27) (thickness 0.15)) (justify left bottom) hide)
    )
    (property "License" "Apache-2.0" (at 147.193 161.29 0)
      (effects (font (size 1.27 1.27) (thickness 0.15)) (justify left bottom) hide)
    )
    (pin "1")
    (instances
      (project "kria-k26-devboard"
        (path ""
          (reference "#PWR053") (unit 1)
        )
      )
    )
  )

  (symbol (lib_id "kria-k26-devboard:GND") (at 171.958 151.13 0) (unit 1)
    (in_bom yes) (on_board yes) (dnp no) (fields_autoplaced)
    (property "Reference" "#PWR054" (at 171.958 157.48 0)
      (effects (font (size 1.27 1.27)) hide)
    )
    (property "Value" "GND" (at 171.958 156.21 0)
      (effects (font (size 1.27 1.27)))
    )
    (property "Footprint" "" (at 180.848 158.75 0)
      (effects (font (size 1.27 1.27) (thickness 0.15)) (justify left bottom) hide)
    )
    (property "Datasheet" "" (at 180.848 163.83 0)
      (effects (font (size 1.27 1.27) (thickness 0.15)) (justify left bottom) hide)
    )
    (property "Author" "Antmicro" (at 180.848 158.75 0)
      (effects (font (size 1.27 1.27) (thickness 0.15)) (justify left bottom) hide)
    )
    (property "License" "Apache-2.0" (at 180.848 161.29 0)
      (effects (font (size 1.27 1.27) (thickness 0.15)) (justify left bottom) hide)
    )
    (pin "1")
    (instances
      (project "kria-k26-devboard"
        (path ""
          (reference "#PWR054") (unit 1)
        )
      )
    )
  )

  (symbol (lib_id "kria-k26-devboard:TP_0.75mm_SMD") (at 196.723 109.22 90) (unit 1)
    (in_bom yes) (on_board yes) (dnp no) (fields_autoplaced)
    (property "Reference" "TP4" (at 198.628 106.0449 90)
      (effects (font (size 1.27 1.27)) (justify right))
    )
    (property "Value" "TP_0.75mm_SMD" (at 199.263 109.22 0)
      (effects (font (size 1.27 1.27) (thickness 0.15)) (justify left bottom) hide)
    )
    (property "Footprint" "kria-k26-devboard-footprints:TP_SMD_0.75mm" (at 191.643 104.14 0)
      (effects (font (size 1.27 1.27) (thickness 0.15)) (justify left bottom) hide)
    )
    (property "Datasheet" "" (at 189.103 104.14 0)
      (effects (font (size 1.27 1.27) (thickness 0.15)) (justify left bottom) hide)
    )
    (property "MPN" "" (at 196.723 109.22 0)
      (effects (font (size 1.27 1.27) (thickness 0.15)) (justify left bottom) hide)
    )
    (property "Manufacturer" "" (at 196.723 109.22 0)
      (effects (font (size 1.27 1.27) (thickness 0.15)) (justify left bottom) hide)
    )
    (property "Author" "Antmicro" (at 211.963 93.98 0)
      (effects (font (size 1.27 1.27) (thickness 0.15)) (justify left bottom) hide)
    )
    (property "License" "Apache-2.0" (at 214.503 93.98 0)
      (effects (font (size 1.27 1.27) (thickness 0.15)) (justify left bottom) hide)
    )
    (pin "1")
    (instances
      (project "kria-k26-devboard"
        (path ""
          (reference "TP4") (unit 1)
        )
      )
    )
  )

  (symbol (lib_id "kria-k26-devboard:TP_0.75mm_SMD") (at 196.723 114.3 270) (unit 1)
    (in_bom yes) (on_board yes) (dnp no) (fields_autoplaced)
    (property "Reference" "TP5" (at 199.263 117.4749 90)
      (effects (font (size 1.27 1.27)) (justify left))
    )
    (property "Value" "TP_0.75mm_SMD" (at 194.183 114.3 0)
      (effects (font (size 1.27 1.27) (thickness 0.15)) (justify left bottom) hide)
    )
    (property "Footprint" "kria-k26-devboard-footprints:TP_SMD_0.75mm" (at 201.803 119.38 0)
      (effects (font (size 1.27 1.27) (thickness 0.15)) (justify left bottom) hide)
    )
    (property "Datasheet" "" (at 204.343 119.38 0)
      (effects (font (size 1.27 1.27) (thickness 0.15)) (justify left bottom) hide)
    )
    (property "MPN" "" (at 196.723 114.3 0)
      (effects (font (size 1.27 1.27) (thickness 0.15)) (justify left bottom) hide)
    )
    (property "Manufacturer" "" (at 196.723 114.3 0)
      (effects (font (size 1.27 1.27) (thickness 0.15)) (justify left bottom) hide)
    )
    (property "Author" "Antmicro" (at 181.483 129.54 0)
      (effects (font (size 1.27 1.27) (thickness 0.15)) (justify left bottom) hide)
    )
    (property "License" "Apache-2.0" (at 178.943 129.54 0)
      (effects (font (size 1.27 1.27) (thickness 0.15)) (justify left bottom) hide)
    )
    (pin "1")
    (instances
      (project "kria-k26-devboard"
        (path ""
          (reference "TP5") (unit 1)
        )
      )
    )
  )

  (symbol (lib_id "kria-k26-devboard:TP_0.75mm_SMD") (at 196.723 125.73 90) (unit 1)
    (in_bom yes) (on_board yes) (dnp no) (fields_autoplaced)
    (property "Reference" "TP6" (at 199.263 122.5549 90)
      (effects (font (size 1.27 1.27)) (justify right))
    )
    (property "Value" "TP_0.75mm_SMD" (at 199.263 125.73 0)
      (effects (font (size 1.27 1.27) (thickness 0.15)) (justify left bottom) hide)
    )
    (property "Footprint" "kria-k26-devboard-footprints:TP_SMD_0.75mm" (at 191.643 120.65 0)
      (effects (font (size 1.27 1.27) (thickness 0.15)) (justify left bottom) hide)
    )
    (property "Datasheet" "" (at 189.103 120.65 0)
      (effects (font (size 1.27 1.27) (thickness 0.15)) (justify left bottom) hide)
    )
    (property "MPN" "" (at 196.723 125.73 0)
      (effects (font (size 1.27 1.27) (thickness 0.15)) (justify left bottom) hide)
    )
    (property "Manufacturer" "" (at 196.723 125.73 0)
      (effects (font (size 1.27 1.27) (thickness 0.15)) (justify left bottom) hide)
    )
    (property "Author" "Antmicro" (at 211.963 110.49 0)
      (effects (font (size 1.27 1.27) (thickness 0.15)) (justify left bottom) hide)
    )
    (property "License" "Apache-2.0" (at 214.503 110.49 0)
      (effects (font (size 1.27 1.27) (thickness 0.15)) (justify left bottom) hide)
    )
    (pin "1")
    (instances
      (project "kria-k26-devboard"
        (path ""
          (reference "TP6") (unit 1)
        )
      )
    )
  )

  (symbol (lib_id "kria-k26-devboard:TP_0.75mm_SMD") (at 196.723 130.81 270) (unit 1)
    (in_bom yes) (on_board yes) (dnp no) (fields_autoplaced)
    (property "Reference" "TP7" (at 199.263 133.9849 90)
      (effects (font (size 1.27 1.27)) (justify left))
    )
    (property "Value" "TP_0.75mm_SMD" (at 194.183 130.81 0)
      (effects (font (size 1.27 1.27) (thickness 0.15)) (justify left bottom) hide)
    )
    (property "Footprint" "kria-k26-devboard-footprints:TP_SMD_0.75mm" (at 201.803 135.89 0)
      (effects (font (size 1.27 1.27) (thickness 0.15)) (justify left bottom) hide)
    )
    (property "Datasheet" "" (at 204.343 135.89 0)
      (effects (font (size 1.27 1.27) (thickness 0.15)) (justify left bottom) hide)
    )
    (property "MPN" "" (at 196.723 130.81 0)
      (effects (font (size 1.27 1.27) (thickness 0.15)) (justify left bottom) hide)
    )
    (property "Manufacturer" "" (at 196.723 130.81 0)
      (effects (font (size 1.27 1.27) (thickness 0.15)) (justify left bottom) hide)
    )
    (property "Author" "Antmicro" (at 181.483 146.05 0)
      (effects (font (size 1.27 1.27) (thickness 0.15)) (justify left bottom) hide)
    )
    (property "License" "Apache-2.0" (at 178.943 146.05 0)
      (effects (font (size 1.27 1.27) (thickness 0.15)) (justify left bottom) hide)
    )
    (pin "1")
    (instances
      (project "kria-k26-devboard"
        (path ""
          (reference "TP7") (unit 1)
        )
      )
    )
  )

  (symbol (lib_id "kria-k26-devboard:TP_0.75mm_SMD") (at 171.958 143.51 90) (unit 1)
    (in_bom yes) (on_board yes) (dnp no) (fields_autoplaced)
    (property "Reference" "TP3" (at 174.498 140.3349 90)
      (effects (font (size 1.27 1.27)) (justify right))
    )
    (property "Value" "TP_0.75mm_SMD" (at 174.498 143.51 0)
      (effects (font (size 1.27 1.27) (thickness 0.15)) (justify left bottom) hide)
    )
    (property "Footprint" "kria-k26-devboard-footprints:TP_SMD_0.75mm" (at 166.878 138.43 0)
      (effects (font (size 1.27 1.27) (thickness 0.15)) (justify left bottom) hide)
    )
    (property "Datasheet" "" (at 164.338 138.43 0)
      (effects (font (size 1.27 1.27) (thickness 0.15)) (justify left bottom) hide)
    )
    (property "MPN" "" (at 171.958 143.51 0)
      (effects (font (size 1.27 1.27) (thickness 0.15)) (justify left bottom) hide)
    )
    (property "Manufacturer" "" (at 171.958 143.51 0)
      (effects (font (size 1.27 1.27) (thickness 0.15)) (justify left bottom) hide)
    )
    (property "Author" "Antmicro" (at 187.198 128.27 0)
      (effects (font (size 1.27 1.27) (thickness 0.15)) (justify left bottom) hide)
    )
    (property "License" "Apache-2.0" (at 189.738 128.27 0)
      (effects (font (size 1.27 1.27) (thickness 0.15)) (justify left bottom) hide)
    )
    (pin "1")
    (instances
      (project "kria-k26-devboard"
        (path ""
          (reference "TP3") (unit 1)
        )
      )
    )
  )

  (symbol (lib_id "kria-k26-devboard:TP_0.75mm_SMD") (at 100.838 121.92 270) (unit 1)
    (in_bom yes) (on_board yes) (dnp no) (fields_autoplaced)
    (property "Reference" "TP2" (at 102.743 125.0949 90)
      (effects (font (size 1.27 1.27)) (justify left))
    )
    (property "Value" "TP_0.75mm_SMD" (at 98.298 121.92 0)
      (effects (font (size 1.27 1.27) (thickness 0.15)) (justify left bottom) hide)
    )
    (property "Footprint" "kria-k26-devboard-footprints:TP_SMD_0.75mm" (at 105.918 127 0)
      (effects (font (size 1.27 1.27) (thickness 0.15)) (justify left bottom) hide)
    )
    (property "Datasheet" "" (at 108.458 127 0)
      (effects (font (size 1.27 1.27) (thickness 0.15)) (justify left bottom) hide)
    )
    (property "MPN" "" (at 100.838 121.92 0)
      (effects (font (size 1.27 1.27) (thickness 0.15)) (justify left bottom) hide)
    )
    (property "Manufacturer" "" (at 100.838 121.92 0)
      (effects (font (size 1.27 1.27) (thickness 0.15)) (justify left bottom) hide)
    )
    (property "Author" "Antmicro" (at 85.598 137.16 0)
      (effects (font (size 1.27 1.27) (thickness 0.15)) (justify left bottom) hide)
    )
    (property "License" "Apache-2.0" (at 83.058 137.16 0)
      (effects (font (size 1.27 1.27) (thickness 0.15)) (justify left bottom) hide)
    )
    (pin "1")
    (instances
      (project "kria-k26-devboard"
        (path ""
          (reference "TP2") (unit 1)
        )
      )
    )
  )

  (symbol (lib_id "kria-k26-devboard:TP_0.75mm_SMD") (at 100.838 116.84 90) (unit 1)
    (in_bom yes) (on_board yes) (dnp no) (fields_autoplaced)
    (property "Reference" "TP1" (at 102.743 113.6649 90)
      (effects (font (size 1.27 1.27)) (justify right))
    )
    (property "Value" "TP_0.75mm_SMD" (at 103.378 116.84 0)
      (effects (font (size 1.27 1.27) (thickness 0.15)) (justify left bottom) hide)
    )
    (property "Footprint" "kria-k26-devboard-footprints:TP_SMD_0.75mm" (at 95.758 111.76 0)
      (effects (font (size 1.27 1.27) (thickness 0.15)) (justify left bottom) hide)
    )
    (property "Datasheet" "" (at 93.218 111.76 0)
      (effects (font (size 1.27 1.27) (thickness 0.15)) (justify left bottom) hide)
    )
    (property "MPN" "" (at 100.838 116.84 0)
      (effects (font (size 1.27 1.27) (thickness 0.15)) (justify left bottom) hide)
    )
    (property "Manufacturer" "" (at 100.838 116.84 0)
      (effects (font (size 1.27 1.27) (thickness 0.15)) (justify left bottom) hide)
    )
    (property "Author" "Antmicro" (at 116.078 101.6 0)
      (effects (font (size 1.27 1.27) (thickness 0.15)) (justify left bottom) hide)
    )
    (property "License" "Apache-2.0" (at 118.618 101.6 0)
      (effects (font (size 1.27 1.27) (thickness 0.15)) (justify left bottom) hide)
    )
    (pin "1")
    (instances
      (project "kria-k26-devboard"
        (path ""
          (reference "TP1") (unit 1)
        )
      )
    )
  )

  (symbol (lib_id "kria-k26-devboard:R_2k2_0402") (at 180.848 120.015 90) (mirror x) (unit 1)
    (in_bom yes) (on_board yes) (dnp no)
    (property "Reference" "R30" (at 178.943 121.285 90)
      (effects (font (size 1.524 1.524)) (justify left))
    )
    (property "Value" "R_2k2_0402" (at 184.658 120.015 0)
      (effects (font (size 1.27 1.27) (thickness 0.15)) (justify left bottom) hide)
    )
    (property "Footprint" "kria-k26-devboard-footprints:R_0402_1005Metric" (at 175.768 125.095 0)
      (effects (font (size 1.27 1.27) (thickness 0.15)) (justify left bottom) hide)
    )
    (property "Datasheet" "https://www.bourns.com/docs/product-datasheets/cr.pdf" (at 180.848 120.015 0)
      (effects (font (size 1.27 1.27) (thickness 0.15)) (justify left bottom) hide)
    )
    (property "Manufacturer" "Bourns" (at 170.688 125.095 0)
      (effects (font (size 1.27 1.27) (thickness 0.15)) (justify left bottom) hide)
    )
    (property "MPN" "CR0402-FX-2201GLF" (at 173.228 125.095 0)
      (effects (font (size 1.27 1.27) (thickness 0.15)) (justify left bottom) hide)
    )
    (property "Val" "2k2" (at 178.943 123.825 90)
      (effects (font (size 1.27 1.27) (thickness 0.15)) (justify left))
    )
    (property "License" "Apache-2.0" (at 206.248 140.335 0)
      (effects (font (size 1.27 1.27) (thickness 0.15)) (justify left bottom) hide)
    )
    (property "Author" "Antmicro" (at 208.788 140.335 0)
      (effects (font (size 1.27 1.27) (thickness 0.15)) (justify left bottom) hide)
    )
    (property "Tolerance" "1%" (at 191.008 140.335 0)
      (effects (font (size 1.27 1.27)) (justify left bottom) hide)
    )
    (pin "1")
    (pin "2")
    (instances
      (project "kria-k26-devboard"
        (path ""
          (reference "R30") (unit 1)
        )
      )
    )
  )

  (symbol (lib_id "kria-k26-devboard:R_2k2_0402") (at 184.658 120.015 270) (unit 1)
    (in_bom yes) (on_board yes) (dnp no)
    (property "Reference" "R32" (at 186.563 121.285 90)
      (effects (font (size 1.524 1.524)) (justify left))
    )
    (property "Value" "R_2k2_0402" (at 180.848 120.015 0)
      (effects (font (size 1.27 1.27) (thickness 0.15)) (justify left bottom) hide)
    )
    (property "Footprint" "kria-k26-devboard-footprints:R_0402_1005Metric" (at 189.738 125.095 0)
      (effects (font (size 1.27 1.27) (thickness 0.15)) (justify left bottom) hide)
    )
    (property "Datasheet" "https://www.bourns.com/docs/product-datasheets/cr.pdf" (at 184.658 120.015 0)
      (effects (font (size 1.27 1.27) (thickness 0.15)) (justify left bottom) hide)
    )
    (property "Manufacturer" "Bourns" (at 194.818 125.095 0)
      (effects (font (size 1.27 1.27) (thickness 0.15)) (justify left bottom) hide)
    )
    (property "MPN" "CR0402-FX-2201GLF" (at 192.278 125.095 0)
      (effects (font (size 1.27 1.27) (thickness 0.15)) (justify left bottom) hide)
    )
    (property "Val" "2k2" (at 186.563 123.825 90)
      (effects (font (size 1.27 1.27) (thickness 0.15)) (justify left))
    )
    (property "License" "Apache-2.0" (at 159.258 140.335 0)
      (effects (font (size 1.27 1.27) (thickness 0.15)) (justify left bottom) hide)
    )
    (property "Author" "Antmicro" (at 156.718 140.335 0)
      (effects (font (size 1.27 1.27) (thickness 0.15)) (justify left bottom) hide)
    )
    (property "Tolerance" "1%" (at 174.498 140.335 0)
      (effects (font (size 1.27 1.27)) (justify left bottom) hide)
    )
    (pin "1")
    (pin "2")
    (instances
      (project "kria-k26-devboard"
        (path ""
          (reference "R32") (unit 1)
        )
      )
    )
  )

  (symbol (lib_id "kria-k26-devboard:R_2k2_0402") (at 180.848 102.87 90) (mirror x) (unit 1)
    (in_bom yes) (on_board yes) (dnp no)
    (property "Reference" "R29" (at 178.943 104.14 90)
      (effects (font (size 1.524 1.524)) (justify left))
    )
    (property "Value" "R_2k2_0402" (at 184.658 102.87 0)
      (effects (font (size 1.27 1.27) (thickness 0.15)) (justify left bottom) hide)
    )
    (property "Footprint" "kria-k26-devboard-footprints:R_0402_1005Metric" (at 175.768 107.95 0)
      (effects (font (size 1.27 1.27) (thickness 0.15)) (justify left bottom) hide)
    )
    (property "Datasheet" "https://www.bourns.com/docs/product-datasheets/cr.pdf" (at 180.848 102.87 0)
      (effects (font (size 1.27 1.27) (thickness 0.15)) (justify left bottom) hide)
    )
    (property "Manufacturer" "Bourns" (at 170.688 107.95 0)
      (effects (font (size 1.27 1.27) (thickness 0.15)) (justify left bottom) hide)
    )
    (property "MPN" "CR0402-FX-2201GLF" (at 173.228 107.95 0)
      (effects (font (size 1.27 1.27) (thickness 0.15)) (justify left bottom) hide)
    )
    (property "Val" "2k2" (at 178.943 106.68 90)
      (effects (font (size 1.27 1.27) (thickness 0.15)) (justify left))
    )
    (property "License" "Apache-2.0" (at 206.248 123.19 0)
      (effects (font (size 1.27 1.27) (thickness 0.15)) (justify left bottom) hide)
    )
    (property "Author" "Antmicro" (at 208.788 123.19 0)
      (effects (font (size 1.27 1.27) (thickness 0.15)) (justify left bottom) hide)
    )
    (property "Tolerance" "1%" (at 191.008 123.19 0)
      (effects (font (size 1.27 1.27)) (justify left bottom) hide)
    )
    (pin "1")
    (pin "2")
    (instances
      (project "kria-k26-devboard"
        (path ""
          (reference "R29") (unit 1)
        )
      )
    )
  )

  (symbol (lib_id "kria-k26-devboard:R_2k2_0402") (at 184.658 102.87 270) (unit 1)
    (in_bom yes) (on_board yes) (dnp no)
    (property "Reference" "R31" (at 186.563 104.14 90)
      (effects (font (size 1.524 1.524)) (justify left))
    )
    (property "Value" "R_2k2_0402" (at 180.848 102.87 0)
      (effects (font (size 1.27 1.27) (thickness 0.15)) (justify left bottom) hide)
    )
    (property "Footprint" "kria-k26-devboard-footprints:R_0402_1005Metric" (at 189.738 107.95 0)
      (effects (font (size 1.27 1.27) (thickness 0.15)) (justify left bottom) hide)
    )
    (property "Datasheet" "https://www.bourns.com/docs/product-datasheets/cr.pdf" (at 184.658 102.87 0)
      (effects (font (size 1.27 1.27) (thickness 0.15)) (justify left bottom) hide)
    )
    (property "Manufacturer" "Bourns" (at 194.818 107.95 0)
      (effects (font (size 1.27 1.27) (thickness 0.15)) (justify left bottom) hide)
    )
    (property "MPN" "CR0402-FX-2201GLF" (at 192.278 107.95 0)
      (effects (font (size 1.27 1.27) (thickness 0.15)) (justify left bottom) hide)
    )
    (property "Val" "2k2" (at 186.563 106.68 90)
      (effects (font (size 1.27 1.27) (thickness 0.15)) (justify left))
    )
    (property "License" "Apache-2.0" (at 159.258 123.19 0)
      (effects (font (size 1.27 1.27) (thickness 0.15)) (justify left bottom) hide)
    )
    (property "Author" "Antmicro" (at 156.718 123.19 0)
      (effects (font (size 1.27 1.27) (thickness 0.15)) (justify left bottom) hide)
    )
    (property "Tolerance" "1%" (at 174.498 123.19 0)
      (effects (font (size 1.27 1.27)) (justify left bottom) hide)
    )
    (pin "1")
    (pin "2")
    (instances
      (project "kria-k26-devboard"
        (path ""
          (reference "R31") (unit 1)
        )
      )
    )
  )

  (symbol (lib_id "kria-k26-devboard:PI4MSD5V9540B_MSOP") (at 119.253 114.3 0) (unit 1)
    (in_bom yes) (on_board yes) (dnp no) (fields_autoplaced)
    (property "Reference" "U10" (at 129.413 106.68 0)
      (effects (font (size 1.27 1.27)))
    )
    (property "Value" "PI4MSD5V9540B_MSOP" (at 129.413 109.22 0)
      (effects (font (size 1.27 1.27) (thickness 0.15)) (justify left bottom))
    )
    (property "Footprint" "kria-k26-devboard-footprints:MSOP-8-1EP_3x3x1.1mm_P0.65mm" (at 115.443 102.87 0)
      (effects (font (size 1.27 1.27) (thickness 0.15)) (justify left bottom) hide)
    )
    (property "Datasheet" "https://www.diodes.com/assets/Datasheets/PI4MSD5V9540B.pdf" (at 119.253 114.3 0)
      (effects (font (size 1.27 1.27) (thickness 0.15)) (justify left bottom) hide)
    )
    (property "Manufacturer" "Diodes Incorporated" (at 124.333 97.79 0)
      (effects (font (size 1.27 1.27) (thickness 0.15)) (justify left bottom) hide)
    )
    (property "MPN" "PI4MSD5V9540BUEX" (at 129.413 109.22 0)
      (effects (font (size 1.27 1.27) (thickness 0.15)) (justify left bottom) hide)
    )
    (property "Author" "Antmicro" (at 154.813 132.08 0)
      (effects (font (size 1.27 1.27) (thickness 0.15)) (justify left bottom) hide)
    )
    (property "License" "Apache-2.0" (at 154.813 134.62 0)
      (effects (font (size 1.27 1.27) (thickness 0.15)) (justify left bottom) hide)
    )
    (pin "1")
    (pin "2")
    (pin "3")
    (pin "4")
    (pin "5")
    (pin "6")
    (pin "7")
    (pin "8")
    (instances
      (project "kria-k26-devboard"
        (path ""
          (reference "U10") (unit 1)
        )
      )
    )
  )

  (symbol (lib_id "kria-k26-devboard:GND") (at 109.093 111.76 0) (unit 1)
    (in_bom yes) (on_board yes) (dnp no) (fields_autoplaced)
    (property "Reference" "#PWR051" (at 109.093 118.11 0)
      (effects (font (size 1.27 1.27)) hide)
    )
    (property "Value" "GND" (at 109.093 116.84 0)
      (effects (font (size 1.27 1.27)))
    )
    (property "Footprint" "" (at 117.983 119.38 0)
      (effects (font (size 1.27 1.27) (thickness 0.15)) (justify left bottom) hide)
    )
    (property "Datasheet" "" (at 117.983 124.46 0)
      (effects (font (size 1.27 1.27) (thickness 0.15)) (justify left bottom) hide)
    )
    (property "Author" "Antmicro" (at 117.983 119.38 0)
      (effects (font (size 1.27 1.27) (thickness 0.15)) (justify left bottom) hide)
    )
    (property "License" "Apache-2.0" (at 117.983 121.92 0)
      (effects (font (size 1.27 1.27) (thickness 0.15)) (justify left bottom) hide)
    )
    (pin "1")
    (instances
      (project "kria-k26-devboard"
        (path ""
          (reference "#PWR051") (unit 1)
        )
      )
    )
  )

  (symbol (lib_id "kria-k26-devboard:GND") (at 112.903 127 0) (unit 1)
    (in_bom yes) (on_board yes) (dnp no) (fields_autoplaced)
    (property "Reference" "#PWR052" (at 112.903 133.35 0)
      (effects (font (size 1.27 1.27)) hide)
    )
    (property "Value" "GND" (at 112.903 132.08 0)
      (effects (font (size 1.27 1.27)))
    )
    (property "Footprint" "" (at 121.793 134.62 0)
      (effects (font (size 1.27 1.27) (thickness 0.15)) (justify left bottom) hide)
    )
    (property "Datasheet" "" (at 121.793 139.7 0)
      (effects (font (size 1.27 1.27) (thickness 0.15)) (justify left bottom) hide)
    )
    (property "Author" "Antmicro" (at 121.793 134.62 0)
      (effects (font (size 1.27 1.27) (thickness 0.15)) (justify left bottom) hide)
    )
    (property "License" "Apache-2.0" (at 121.793 137.16 0)
      (effects (font (size 1.27 1.27) (thickness 0.15)) (justify left bottom) hide)
    )
    (pin "1")
    (instances
      (project "kria-k26-devboard"
        (path ""
          (reference "#PWR052") (unit 1)
        )
      )
    )
  )

  (symbol (lib_id "kria-k26-devboard:R_2k2_0402") (at 95.123 106.68 270) (unit 1)
    (in_bom yes) (on_board yes) (dnp no) (fields_autoplaced)
    (property "Reference" "R24" (at 97.663 107.95 90)
      (effects (font (size 1.524 1.524)) (justify left))
    )
    (property "Value" "R_2k2_0402" (at 91.313 106.68 0)
      (effects (font (size 1.27 1.27) (thickness 0.15)) (justify left bottom) hide)
    )
    (property "Footprint" "kria-k26-devboard-footprints:R_0402_1005Metric" (at 100.203 111.76 0)
      (effects (font (size 1.27 1.27) (thickness 0.15)) (justify left bottom) hide)
    )
    (property "Datasheet" "https://www.bourns.com/docs/product-datasheets/cr.pdf" (at 95.123 106.68 0)
      (effects (font (size 1.27 1.27) (thickness 0.15)) (justify left bottom) hide)
    )
    (property "Manufacturer" "Bourns" (at 105.283 111.76 0)
      (effects (font (size 1.27 1.27) (thickness 0.15)) (justify left bottom) hide)
    )
    (property "MPN" "CR0402-FX-2201GLF" (at 102.743 111.76 0)
      (effects (font (size 1.27 1.27) (thickness 0.15)) (justify left bottom) hide)
    )
    (property "Val" "2k2" (at 97.663 111.1249 90)
      (effects (font (size 1.27 1.27) (thickness 0.15)) (justify left))
    )
    (property "License" "Apache-2.0" (at 69.723 127 0)
      (effects (font (size 1.27 1.27) (thickness 0.15)) (justify left bottom) hide)
    )
    (property "Author" "Antmicro" (at 67.183 127 0)
      (effects (font (size 1.27 1.27) (thickness 0.15)) (justify left bottom) hide)
    )
    (property "Tolerance" "1%" (at 84.963 127 0)
      (effects (font (size 1.27 1.27)) (justify left bottom) hide)
    )
    (pin "1")
    (pin "2")
    (instances
      (project "kria-k26-devboard"
        (path ""
          (reference "R24") (unit 1)
        )
      )
    )
  )

  (symbol (lib_id "kria-k26-devboard:R_2k2_0402") (at 91.313 106.68 90) (mirror x) (unit 1)
    (in_bom yes) (on_board yes) (dnp no) (fields_autoplaced)
    (property "Reference" "R23" (at 88.773 107.95 90)
      (effects (font (size 1.524 1.524)) (justify left))
    )
    (property "Value" "R_2k2_0402" (at 95.123 106.68 0)
      (effects (font (size 1.27 1.27) (thickness 0.15)) (justify left bottom) hide)
    )
    (property "Footprint" "kria-k26-devboard-footprints:R_0402_1005Metric" (at 86.233 111.76 0)
      (effects (font (size 1.27 1.27) (thickness 0.15)) (justify left bottom) hide)
    )
    (property "Datasheet" "https://www.bourns.com/docs/product-datasheets/cr.pdf" (at 91.313 106.68 0)
      (effects (font (size 1.27 1.27) (thickness 0.15)) (justify left bottom) hide)
    )
    (property "Manufacturer" "Bourns" (at 81.153 111.76 0)
      (effects (font (size 1.27 1.27) (thickness 0.15)) (justify left bottom) hide)
    )
    (property "MPN" "CR0402-FX-2201GLF" (at 83.693 111.76 0)
      (effects (font (size 1.27 1.27) (thickness 0.15)) (justify left bottom) hide)
    )
    (property "Val" "2k2" (at 88.773 111.1249 90)
      (effects (font (size 1.27 1.27) (thickness 0.15)) (justify left))
    )
    (property "License" "Apache-2.0" (at 116.713 127 0)
      (effects (font (size 1.27 1.27) (thickness 0.15)) (justify left bottom) hide)
    )
    (property "Author" "Antmicro" (at 119.253 127 0)
      (effects (font (size 1.27 1.27) (thickness 0.15)) (justify left bottom) hide)
    )
    (property "Tolerance" "1%" (at 101.473 127 0)
      (effects (font (size 1.27 1.27)) (justify left bottom) hide)
    )
    (pin "1")
    (pin "2")
    (instances
      (project "kria-k26-devboard"
        (path ""
          (reference "R23") (unit 1)
        )
      )
    )
  )

  (symbol (lib_id "kria-k26-devboard:C_100n_0402") (at 109.093 106.68 90) (mirror x) (unit 1)
    (in_bom yes) (on_board yes) (dnp no) (fields_autoplaced)
    (property "Reference" "C29" (at 111.633 107.9563 90)
      (effects (font (size 1.524 1.524)) (justify right))
    )
    (property "Value" "C_100n_0402" (at 112.903 106.68 0)
      (effects (font (size 1.27 1.27) (thickness 0.15)) (justify left bottom) hide)
    )
    (property "Footprint" "kria-k26-devboard-footprints:C_0402_1005Metric" (at 104.013 111.76 0)
      (effects (font (size 1.27 1.27) (thickness 0.15)) (justify left bottom) hide)
    )
    (property "Datasheet" "https://search.murata.co.jp/Ceramy/image/img/A01X/G101/ENG/GRM155R61H104KE14-01.pdf" (at 109.093 106.68 0)
      (effects (font (size 1.27 1.27) (thickness 0.15)) (justify left bottom) hide)
    )
    (property "Manufacturer" "Murata" (at 98.933 111.76 0)
      (effects (font (size 1.27 1.27) (thickness 0.15)) (justify left bottom) hide)
    )
    (property "MPN" "GRM155R61H104KE14D" (at 101.473 111.76 0)
      (effects (font (size 1.27 1.27) (thickness 0.15)) (justify left bottom) hide)
    )
    (property "Val" "100n" (at 111.633 111.1312 90)
      (effects (font (size 1.27 1.27) (thickness 0.15)) (justify right))
    )
    (property "License" "Apache-2.0" (at 131.953 127 0)
      (effects (font (size 1.27 1.27) (thickness 0.15)) (justify left bottom) hide)
    )
    (property "Author" "Antmicro" (at 134.493 127 0)
      (effects (font (size 1.27 1.27) (thickness 0.15)) (justify left bottom) hide)
    )
    (property "Voltage" "50V" (at 137.033 127 0)
      (effects (font (size 1.27 1.27)) (justify left bottom) hide)
    )
    (property "Dielectric" "X5R" (at 139.573 127 0)
      (effects (font (size 1.27 1.27)) (justify left bottom) hide)
    )
    (pin "1")
    (pin "2")
    (instances
      (project "kria-k26-devboard"
        (path ""
          (reference "C29") (unit 1)
        )
      )
    )
  )

  (symbol (lib_id "kria-k26-devboard:GND") (at 269.24 212.09 0) (unit 1)
    (in_bom yes) (on_board yes) (dnp no) (fields_autoplaced)
    (property "Reference" "#PWR055" (at 269.24 218.44 0)
      (effects (font (size 1.27 1.27)) hide)
    )
    (property "Value" "GND" (at 269.24 217.17 0)
      (effects (font (size 1.27 1.27)))
    )
    (property "Footprint" "" (at 278.13 219.71 0)
      (effects (font (size 1.27 1.27) (thickness 0.15)) (justify left bottom) hide)
    )
    (property "Datasheet" "" (at 278.13 224.79 0)
      (effects (font (size 1.27 1.27) (thickness 0.15)) (justify left bottom) hide)
    )
    (property "Author" "Antmicro" (at 278.13 219.71 0)
      (effects (font (size 1.27 1.27) (thickness 0.15)) (justify left bottom) hide)
    )
    (property "License" "Apache-2.0" (at 278.13 222.25 0)
      (effects (font (size 1.27 1.27) (thickness 0.15)) (justify left bottom) hide)
    )
    (pin "1")
    (instances
      (project "kria-k26-devboard"
        (path ""
          (reference "#PWR055") (unit 1)
        )
      )
    )
  )

  (symbol (lib_id "kria-k26-devboard:C_10u_0603") (at 153.67 171.45 270) (unit 1)
    (in_bom yes) (on_board yes) (dnp no) (fields_autoplaced)
    (property "Reference" "C245" (at 156.21 172.7263 90)
      (effects (font (size 1.524 1.524)) (justify left))
    )
    (property "Value" "C_10u_0603" (at 149.86 171.45 0)
      (effects (font (size 1.27 1.27) (thickness 0.15)) (justify left bottom) hide)
    )
    (property "Footprint" "kria-k26-devboard-footprints:C_0603_1608Metric" (at 158.75 176.53 0)
      (effects (font (size 1.27 1.27) (thickness 0.15)) (justify left bottom) hide)
    )
    (property "Datasheet" " " (at 153.67 171.45 0)
      (effects (font (size 1.27 1.27) (thickness 0.15)) (justify left bottom) hide)
    )
    (property "Manufacturer" "Murata" (at 163.83 176.53 0)
      (effects (font (size 1.27 1.27) (thickness 0.15)) (justify left bottom) hide)
    )
    (property "MPN" "GRM188R61A106KE69D" (at 161.29 176.53 0)
      (effects (font (size 1.27 1.27) (thickness 0.15)) (justify left bottom) hide)
    )
    (property "Val" "10u" (at 156.21 175.9012 90)
      (effects (font (size 1.27 1.27) (thickness 0.15)) (justify left))
    )
    (property "License" "Apache-2.0" (at 130.81 191.77 0)
      (effects (font (size 1.27 1.27) (thickness 0.15)) (justify left bottom) hide)
    )
    (property "Author" "Antmicro" (at 128.27 191.77 0)
      (effects (font (size 1.27 1.27) (thickness 0.15)) (justify left bottom) hide)
    )
    (property "Voltage" "" (at 125.73 191.77 0)
      (effects (font (size 1.27 1.27)) (justify left bottom) hide)
    )
    (pin "1")
    (pin "2")
    (instances
      (project "kria-k26-devboard"
        (path ""
          (reference "C245") (unit 1)
        )
      )
    )
  )

  (symbol (lib_id "kria-k26-devboard:C_100n_0402") (at 140.97 171.45 270) (unit 1)
    (in_bom yes) (on_board yes) (dnp no) (fields_autoplaced)
    (property "Reference" "C244" (at 144.145 172.7263 90)
      (effects (font (size 1.524 1.524)) (justify left))
    )
    (property "Value" "C_100n_0402" (at 137.16 171.45 0)
      (effects (font (size 1.27 1.27) (thickness 0.15)) (justify left bottom) hide)
    )
    (property "Footprint" "kria-k26-devboard-footprints:C_0402_1005Metric" (at 146.05 176.53 0)
      (effects (font (size 1.27 1.27) (thickness 0.15)) (justify left bottom) hide)
    )
    (property "Datasheet" "https://search.murata.co.jp/Ceramy/image/img/A01X/G101/ENG/GRM155R61H104KE14-01.pdf" (at 140.97 171.45 0)
      (effects (font (size 1.27 1.27) (thickness 0.15)) (justify left bottom) hide)
    )
    (property "Manufacturer" "Murata" (at 151.13 176.53 0)
      (effects (font (size 1.27 1.27) (thickness 0.15)) (justify left bottom) hide)
    )
    (property "MPN" "GRM155R61H104KE14D" (at 148.59 176.53 0)
      (effects (font (size 1.27 1.27) (thickness 0.15)) (justify left bottom) hide)
    )
    (property "Val" "100n" (at 144.145 175.9012 90)
      (effects (font (size 1.27 1.27) (thickness 0.15)) (justify left))
    )
    (property "License" "Apache-2.0" (at 118.11 191.77 0)
      (effects (font (size 1.27 1.27) (thickness 0.15)) (justify left bottom) hide)
    )
    (property "Author" "Antmicro" (at 115.57 191.77 0)
      (effects (font (size 1.27 1.27) (thickness 0.15)) (justify left bottom) hide)
    )
    (property "Voltage" "50V" (at 113.03 191.77 0)
      (effects (font (size 1.27 1.27)) (justify left bottom) hide)
    )
    (property "Dielectric" "X5R" (at 110.49 191.77 0)
      (effects (font (size 1.27 1.27)) (justify left bottom) hide)
    )
    (pin "1")
    (pin "2")
    (instances
      (project "kria-k26-devboard"
        (path ""
          (reference "C244") (unit 1)
        )
      )
    )
  )

  (symbol (lib_id "kria-k26-devboard:C_100n_0402") (at 167.005 171.45 270) (unit 1)
    (in_bom yes) (on_board yes) (dnp no) (fields_autoplaced)
    (property "Reference" "C246" (at 170.18 172.7263 90)
      (effects (font (size 1.524 1.524)) (justify left))
    )
    (property "Value" "C_100n_0402" (at 163.195 171.45 0)
      (effects (font (size 1.27 1.27) (thickness 0.15)) (justify left bottom) hide)
    )
    (property "Footprint" "kria-k26-devboard-footprints:C_0402_1005Metric" (at 172.085 176.53 0)
      (effects (font (size 1.27 1.27) (thickness 0.15)) (justify left bottom) hide)
    )
    (property "Datasheet" "https://search.murata.co.jp/Ceramy/image/img/A01X/G101/ENG/GRM155R61H104KE14-01.pdf" (at 167.005 171.45 0)
      (effects (font (size 1.27 1.27) (thickness 0.15)) (justify left bottom) hide)
    )
    (property "Manufacturer" "Murata" (at 177.165 176.53 0)
      (effects (font (size 1.27 1.27) (thickness 0.15)) (justify left bottom) hide)
    )
    (property "MPN" "GRM155R61H104KE14D" (at 174.625 176.53 0)
      (effects (font (size 1.27 1.27) (thickness 0.15)) (justify left bottom) hide)
    )
    (property "Val" "100n" (at 170.18 175.9012 90)
      (effects (font (size 1.27 1.27) (thickness 0.15)) (justify left))
    )
    (property "License" "Apache-2.0" (at 144.145 191.77 0)
      (effects (font (size 1.27 1.27) (thickness 0.15)) (justify left bottom) hide)
    )
    (property "Author" "Antmicro" (at 141.605 191.77 0)
      (effects (font (size 1.27 1.27) (thickness 0.15)) (justify left bottom) hide)
    )
    (property "Voltage" "50V" (at 139.065 191.77 0)
      (effects (font (size 1.27 1.27)) (justify left bottom) hide)
    )
    (property "Dielectric" "X5R" (at 136.525 191.77 0)
      (effects (font (size 1.27 1.27)) (justify left bottom) hide)
    )
    (pin "1")
    (pin "2")
    (instances
      (project "kria-k26-devboard"
        (path ""
          (reference "C246") (unit 1)
        )
      )
    )
  )

  (symbol (lib_id "kria-k26-devboard:GND") (at 148.463 151.13 0) (unit 1)
    (in_bom yes) (on_board yes) (dnp no) (fields_autoplaced)
    (property "Reference" "#PWR0186" (at 148.463 157.48 0)
      (effects (font (size 1.27 1.27)) hide)
    )
    (property "Value" "GND" (at 148.463 156.21 0)
      (effects (font (size 1.27 1.27)))
    )
    (property "Footprint" "" (at 157.353 158.75 0)
      (effects (font (size 1.27 1.27) (thickness 0.15)) (justify left bottom) hide)
    )
    (property "Datasheet" "" (at 157.353 163.83 0)
      (effects (font (size 1.27 1.27) (thickness 0.15)) (justify left bottom) hide)
    )
    (property "Author" "Antmicro" (at 157.353 158.75 0)
      (effects (font (size 1.27 1.27) (thickness 0.15)) (justify left bottom) hide)
    )
    (property "License" "Apache-2.0" (at 157.353 161.29 0)
      (effects (font (size 1.27 1.27) (thickness 0.15)) (justify left bottom) hide)
    )
    (pin "1")
    (instances
      (project "kria-k26-devboard"
        (path ""
          (reference "#PWR0186") (unit 1)
        )
      )
    )
  )

  (symbol (lib_id "kria-k26-devboard:GND") (at 140.97 176.53 0) (unit 1)
    (in_bom yes) (on_board yes) (dnp no) (fields_autoplaced)
    (property "Reference" "#PWR0210" (at 140.97 182.88 0)
      (effects (font (size 1.27 1.27)) hide)
    )
    (property "Value" "GND" (at 140.97 181.61 0)
      (effects (font (size 1.27 1.27)))
    )
    (property "Footprint" "" (at 149.86 184.15 0)
      (effects (font (size 1.27 1.27) (thickness 0.15)) (justify left bottom) hide)
    )
    (property "Datasheet" "" (at 149.86 189.23 0)
      (effects (font (size 1.27 1.27) (thickness 0.15)) (justify left bottom) hide)
    )
    (property "Author" "Antmicro" (at 149.86 184.15 0)
      (effects (font (size 1.27 1.27) (thickness 0.15)) (justify left bottom) hide)
    )
    (property "License" "Apache-2.0" (at 149.86 186.69 0)
      (effects (font (size 1.27 1.27) (thickness 0.15)) (justify left bottom) hide)
    )
    (pin "1")
    (instances
      (project "kria-k26-devboard"
        (path ""
          (reference "#PWR0210") (unit 1)
        )
      )
    )
  )

  (symbol (lib_id "kria-k26-devboard:C_10u_0603") (at 179.705 171.45 270) (unit 1)
    (in_bom yes) (on_board yes) (dnp no) (fields_autoplaced)
    (property "Reference" "C247" (at 182.88 172.7263 90)
      (effects (font (size 1.524 1.524)) (justify left))
    )
    (property "Value" "C_10u_0603" (at 175.895 171.45 0)
      (effects (font (size 1.27 1.27) (thickness 0.15)) (justify left bottom) hide)
    )
    (property "Footprint" "kria-k26-devboard-footprints:C_0603_1608Metric" (at 184.785 176.53 0)
      (effects (font (size 1.27 1.27) (thickness 0.15)) (justify left bottom) hide)
    )
    (property "Datasheet" " " (at 179.705 171.45 0)
      (effects (font (size 1.27 1.27) (thickness 0.15)) (justify left bottom) hide)
    )
    (property "Manufacturer" "Murata" (at 189.865 176.53 0)
      (effects (font (size 1.27 1.27) (thickness 0.15)) (justify left bottom) hide)
    )
    (property "MPN" "GRM188R61A106KE69D" (at 187.325 176.53 0)
      (effects (font (size 1.27 1.27) (thickness 0.15)) (justify left bottom) hide)
    )
    (property "Val" "10u" (at 182.88 175.9012 90)
      (effects (font (size 1.27 1.27) (thickness 0.15)) (justify left))
    )
    (property "License" "Apache-2.0" (at 156.845 191.77 0)
      (effects (font (size 1.27 1.27) (thickness 0.15)) (justify left bottom) hide)
    )
    (property "Author" "Antmicro" (at 154.305 191.77 0)
      (effects (font (size 1.27 1.27) (thickness 0.15)) (justify left bottom) hide)
    )
    (property "Voltage" "" (at 151.765 191.77 0)
      (effects (font (size 1.27 1.27)) (justify left bottom) hide)
    )
    (pin "1")
    (pin "2")
    (instances
      (project "kria-k26-devboard"
        (path ""
          (reference "C247") (unit 1)
        )
      )
    )
  )

  (symbol (lib_id "kria-k26-devboard:GND") (at 167.005 176.53 0) (unit 1)
    (in_bom yes) (on_board yes) (dnp no) (fields_autoplaced)
    (property "Reference" "#PWR0185" (at 167.005 182.88 0)
      (effects (font (size 1.27 1.27)) hide)
    )
    (property "Value" "GND" (at 167.005 180.975 0)
      (effects (font (size 1.27 1.27)))
    )
    (property "Footprint" "" (at 175.895 184.15 0)
      (effects (font (size 1.27 1.27) (thickness 0.15)) (justify left bottom) hide)
    )
    (property "Datasheet" "" (at 175.895 189.23 0)
      (effects (font (size 1.27 1.27) (thickness 0.15)) (justify left bottom) hide)
    )
    (property "Author" "Antmicro" (at 175.895 184.15 0)
      (effects (font (size 1.27 1.27) (thickness 0.15)) (justify left bottom) hide)
    )
    (property "License" "Apache-2.0" (at 175.895 186.69 0)
      (effects (font (size 1.27 1.27) (thickness 0.15)) (justify left bottom) hide)
    )
    (pin "1")
    (instances
      (project "kria-k26-devboard"
        (path ""
          (reference "#PWR0185") (unit 1)
        )
      )
    )
  )

  (symbol (lib_id "kria-k26-devboard:GND") (at 153.67 176.53 0) (unit 1)
    (in_bom yes) (on_board yes) (dnp no) (fields_autoplaced)
    (property "Reference" "#PWR0408" (at 153.67 182.88 0)
      (effects (font (size 1.27 1.27)) hide)
    )
    (property "Value" "GND" (at 153.67 181.61 0)
      (effects (font (size 1.27 1.27)))
    )
    (property "Footprint" "" (at 162.56 184.15 0)
      (effects (font (size 1.27 1.27) (thickness 0.15)) (justify left bottom) hide)
    )
    (property "Datasheet" "" (at 162.56 189.23 0)
      (effects (font (size 1.27 1.27) (thickness 0.15)) (justify left bottom) hide)
    )
    (property "Author" "Antmicro" (at 162.56 184.15 0)
      (effects (font (size 1.27 1.27) (thickness 0.15)) (justify left bottom) hide)
    )
    (property "License" "Apache-2.0" (at 162.56 186.69 0)
      (effects (font (size 1.27 1.27) (thickness 0.15)) (justify left bottom) hide)
    )
    (pin "1")
    (instances
      (project "kria-k26-devboard"
        (path ""
          (reference "#PWR0408") (unit 1)
        )
      )
    )
  )

  (symbol (lib_id "kria-k26-devboard:GND") (at 179.705 176.53 0) (unit 1)
    (in_bom yes) (on_board yes) (dnp no) (fields_autoplaced)
    (property "Reference" "#PWR0407" (at 179.705 182.88 0)
      (effects (font (size 1.27 1.27)) hide)
    )
    (property "Value" "GND" (at 179.705 180.975 0)
      (effects (font (size 1.27 1.27)))
    )
    (property "Footprint" "" (at 188.595 184.15 0)
      (effects (font (size 1.27 1.27) (thickness 0.15)) (justify left bottom) hide)
    )
    (property "Datasheet" "" (at 188.595 189.23 0)
      (effects (font (size 1.27 1.27) (thickness 0.15)) (justify left bottom) hide)
    )
    (property "Author" "Antmicro" (at 188.595 184.15 0)
      (effects (font (size 1.27 1.27) (thickness 0.15)) (justify left bottom) hide)
    )
    (property "License" "Apache-2.0" (at 188.595 186.69 0)
      (effects (font (size 1.27 1.27) (thickness 0.15)) (justify left bottom) hide)
    )
    (pin "1")
    (instances
      (project "kria-k26-devboard"
        (path ""
          (reference "#PWR0407") (unit 1)
        )
      )
    )
  )

  (symbol (lib_id "kria-k26-devboard:GND") (at 166.243 151.13 0) (mirror y) (unit 1)
    (in_bom yes) (on_board yes) (dnp no) (fields_autoplaced)
    (property "Reference" "#PWR0184" (at 166.243 157.48 0)
      (effects (font (size 1.27 1.27)) hide)
    )
    (property "Value" "GND" (at 166.243 156.21 0)
      (effects (font (size 1.27 1.27)))
    )
    (property "Footprint" "" (at 157.353 158.75 0)
      (effects (font (size 1.27 1.27) (thickness 0.15)) (justify left bottom) hide)
    )
    (property "Datasheet" "" (at 157.353 163.83 0)
      (effects (font (size 1.27 1.27) (thickness 0.15)) (justify left bottom) hide)
    )
    (property "Author" "Antmicro" (at 157.353 158.75 0)
      (effects (font (size 1.27 1.27) (thickness 0.15)) (justify left bottom) hide)
    )
    (property "License" "Apache-2.0" (at 157.353 161.29 0)
      (effects (font (size 1.27 1.27) (thickness 0.15)) (justify left bottom) hide)
    )
    (pin "1")
    (instances
      (project "kria-k26-devboard"
        (path ""
          (reference "#PWR0184") (unit 1)
        )
      )
    )
  )
)
